FILE_TYPE = MACRO_DRAWING;
SET COLOR_WIRE YELLOW;
SET COLOR_PROP MONO;
SET COLOR_DOT WHITE;
SET COLOR_ARC YELLOW;
SET COLOR_BODY GREEN;
SET COLOR_NOTE MONO;
SET PROP_DISPLAY VALUE;
SET PAGE_NUMBER P30;
FORCEADD TAP..1
R 2
(-5825 1900);
FORCEPROP 3 LASTPIN (-5775 1900) SIG_NAME P3E_CPU0_PE1_SS_RXP<1>
J 0
(-5765 1910);
DISPLAY 0.659574 (-5765 1910);
PAINT MONO (-5765 1910);
DISPLAY INVISIBLE (-5765 1910);
FORCEPROP 1 LASTPIN (-5775 1900) BN 1
J 2
(-5763 1908);
DISPLAY 0.617021 (-5763 1908);
PAINT PINK (-5763 1908);
FORCEPROP 1 LAST PATH I1
J 2
(-5823 1900);
DISPLAY 0.872340 (-5823 1900);
PAINT GREEN (-5823 1900);
DISPLAY INVISIBLE (-5823 1900);
FORCEPROP 1 LAST HDL_TAP TRUE
J 2
(-6150 1775);
DISPLAY 1.446809 (-6150 1775);
PAINT GREEN (-6150 1775);
DISPLAY INVISIBLE (-6150 1775);
FORCEPROP 1 LAST BODY_TYPE PLUMBING
J 2
(-5825 1950);
DISPLAY 1.446809 (-5825 1950);
PAINT GREEN (-5825 1950);
DISPLAY INVISIBLE (-5825 1950);
FORCEPROP 2 LAST CDS_LIB mstr_standard
J 0
(-5825 1900);
PAINT MONO (-5825 1900);
DISPLAY INVISIBLE (-5825 1900);
FORCEADD TAP..1
R 2
(-5825 2500);
FORCEPROP 3 LASTPIN (-5775 2500) SIG_NAME P3E_CPU0_PE1_SS_RXP<7>
J 0
(-5765 2510);
DISPLAY 0.659574 (-5765 2510);
PAINT MONO (-5765 2510);
DISPLAY INVISIBLE (-5765 2510);
FORCEPROP 1 LASTPIN (-5775 2500) BN 7
J 2
(-5763 2508);
DISPLAY 0.617021 (-5763 2508);
PAINT PINK (-5763 2508);
FORCEPROP 1 LAST PATH I10
J 2
(-5823 2500);
DISPLAY 0.872340 (-5823 2500);
PAINT GREEN (-5823 2500);
DISPLAY INVISIBLE (-5823 2500);
FORCEPROP 1 LAST HDL_TAP TRUE
J 2
(-6150 2375);
DISPLAY 1.446809 (-6150 2375);
PAINT GREEN (-6150 2375);
DISPLAY INVISIBLE (-6150 2375);
FORCEPROP 1 LAST BODY_TYPE PLUMBING
J 2
(-5825 2550);
DISPLAY 1.446809 (-5825 2550);
PAINT GREEN (-5825 2550);
DISPLAY INVISIBLE (-5825 2550);
FORCEPROP 2 LAST CDS_LIB mstr_standard
J 0
(-5825 2500);
PAINT MONO (-5825 2500);
DISPLAY INVISIBLE (-5825 2500);
FORCEADD TAP..1
R 2
(-5825 2850);
FORCEPROP 3 LASTPIN (-5775 2850) SIG_NAME P3E_CPU0_PE1_PCH_RXP<8>
J 0
(-5765 2860);
DISPLAY 0.659574 (-5765 2860);
PAINT MONO (-5765 2860);
DISPLAY INVISIBLE (-5765 2860);
FORCEPROP 1 LASTPIN (-5775 2850) BN 8
J 2
(-5763 2858);
DISPLAY 0.617021 (-5763 2858);
PAINT PINK (-5763 2858);
FORCEPROP 1 LAST PATH I11
J 2
(-5823 2850);
DISPLAY 0.872340 (-5823 2850);
PAINT GREEN (-5823 2850);
DISPLAY INVISIBLE (-5823 2850);
FORCEPROP 1 LAST HDL_TAP TRUE
J 2
(-6150 2725);
DISPLAY 1.446809 (-6150 2725);
PAINT GREEN (-6150 2725);
DISPLAY INVISIBLE (-6150 2725);
FORCEPROP 1 LAST BODY_TYPE PLUMBING
J 2
(-5825 2900);
DISPLAY 1.446809 (-5825 2900);
PAINT GREEN (-5825 2900);
DISPLAY INVISIBLE (-5825 2900);
FORCEPROP 2 LAST CDS_LIB mstr_standard
J 0
(-5825 2850);
PAINT MONO (-5825 2850);
DISPLAY INVISIBLE (-5825 2850);
FORCEADD TAP..1
R 2
(-5825 2900);
FORCEPROP 3 LASTPIN (-5775 2900) SIG_NAME P3E_CPU0_PE1_PCH_RXP<9>
J 0
(-5765 2910);
DISPLAY 0.659574 (-5765 2910);
PAINT MONO (-5765 2910);
DISPLAY INVISIBLE (-5765 2910);
FORCEPROP 1 LASTPIN (-5775 2900) BN 9
J 2
(-5763 2908);
DISPLAY 0.617021 (-5763 2908);
PAINT PINK (-5763 2908);
FORCEPROP 1 LAST PATH I12
J 2
(-5823 2900);
DISPLAY 0.872340 (-5823 2900);
PAINT GREEN (-5823 2900);
DISPLAY INVISIBLE (-5823 2900);
FORCEPROP 1 LAST HDL_TAP TRUE
J 2
(-6150 2775);
DISPLAY 1.446809 (-6150 2775);
PAINT GREEN (-6150 2775);
DISPLAY INVISIBLE (-6150 2775);
FORCEPROP 1 LAST BODY_TYPE PLUMBING
J 2
(-5825 2950);
DISPLAY 1.446809 (-5825 2950);
PAINT GREEN (-5825 2950);
DISPLAY INVISIBLE (-5825 2950);
FORCEPROP 2 LAST CDS_LIB mstr_standard
J 0
(-5825 2900);
PAINT MONO (-5825 2900);
DISPLAY INVISIBLE (-5825 2900);
FORCEADD TAP..1
R 2
(-5825 2950);
FORCEPROP 3 LASTPIN (-5775 2950) SIG_NAME P3E_CPU0_PE1_PCH_RXP<10>
J 0
(-5765 2960);
DISPLAY 0.659574 (-5765 2960);
PAINT MONO (-5765 2960);
DISPLAY INVISIBLE (-5765 2960);
FORCEPROP 1 LASTPIN (-5775 2950) BN 10
J 2
(-5763 2958);
DISPLAY 0.617021 (-5763 2958);
PAINT PINK (-5763 2958);
FORCEPROP 1 LAST PATH I13
J 2
(-5823 2950);
DISPLAY 0.872340 (-5823 2950);
PAINT GREEN (-5823 2950);
DISPLAY INVISIBLE (-5823 2950);
FORCEPROP 1 LAST HDL_TAP TRUE
J 2
(-6150 2825);
DISPLAY 1.446809 (-6150 2825);
PAINT GREEN (-6150 2825);
DISPLAY INVISIBLE (-6150 2825);
FORCEPROP 1 LAST BODY_TYPE PLUMBING
J 2
(-5825 3000);
DISPLAY 1.446809 (-5825 3000);
PAINT GREEN (-5825 3000);
DISPLAY INVISIBLE (-5825 3000);
FORCEPROP 2 LAST CDS_LIB mstr_standard
J 0
(-5825 2950);
PAINT MONO (-5825 2950);
DISPLAY INVISIBLE (-5825 2950);
FORCEADD TAP..1
R 2
(-5825 3000);
FORCEPROP 3 LASTPIN (-5775 3000) SIG_NAME P3E_CPU0_PE1_PCH_RXP<11>
J 0
(-5765 3010);
DISPLAY 0.659574 (-5765 3010);
PAINT MONO (-5765 3010);
DISPLAY INVISIBLE (-5765 3010);
FORCEPROP 1 LASTPIN (-5775 3000) BN 11
J 2
(-5763 3008);
DISPLAY 0.617021 (-5763 3008);
PAINT PINK (-5763 3008);
FORCEPROP 1 LAST PATH I14
J 2
(-5823 3000);
DISPLAY 0.872340 (-5823 3000);
PAINT GREEN (-5823 3000);
DISPLAY INVISIBLE (-5823 3000);
FORCEPROP 1 LAST HDL_TAP TRUE
J 2
(-6150 2875);
DISPLAY 1.446809 (-6150 2875);
PAINT GREEN (-6150 2875);
DISPLAY INVISIBLE (-6150 2875);
FORCEPROP 1 LAST BODY_TYPE PLUMBING
J 2
(-5825 3050);
DISPLAY 1.446809 (-5825 3050);
PAINT GREEN (-5825 3050);
DISPLAY INVISIBLE (-5825 3050);
FORCEPROP 2 LAST CDS_LIB mstr_standard
J 0
(-5825 3000);
PAINT MONO (-5825 3000);
DISPLAY INVISIBLE (-5825 3000);
FORCEADD TAP..1
R 2
(-5825 3350);
FORCEPROP 3 LASTPIN (-5775 3350) SIG_NAME P3E_CPU0_PE1_PCH_RXP<12>
J 0
(-5765 3360);
DISPLAY 0.659574 (-5765 3360);
PAINT MONO (-5765 3360);
DISPLAY INVISIBLE (-5765 3360);
FORCEPROP 1 LASTPIN (-5775 3350) BN 12
J 2
(-5763 3358);
DISPLAY 0.617021 (-5763 3358);
PAINT PINK (-5763 3358);
FORCEPROP 1 LAST PATH I15
J 2
(-5823 3350);
DISPLAY 0.872340 (-5823 3350);
PAINT GREEN (-5823 3350);
DISPLAY INVISIBLE (-5823 3350);
FORCEPROP 1 LAST HDL_TAP TRUE
J 2
(-6150 3225);
DISPLAY 1.446809 (-6150 3225);
PAINT GREEN (-6150 3225);
DISPLAY INVISIBLE (-6150 3225);
FORCEPROP 1 LAST BODY_TYPE PLUMBING
J 2
(-5825 3400);
DISPLAY 1.446809 (-5825 3400);
PAINT GREEN (-5825 3400);
DISPLAY INVISIBLE (-5825 3400);
FORCEPROP 2 LAST CDS_LIB mstr_standard
J 0
(-5825 3350);
PAINT MONO (-5825 3350);
DISPLAY INVISIBLE (-5825 3350);
FORCEADD TAP..1
R 2
(-5825 3400);
FORCEPROP 3 LASTPIN (-5775 3400) SIG_NAME P3E_CPU0_PE1_PCH_RXP<13>
J 0
(-5765 3410);
DISPLAY 0.659574 (-5765 3410);
PAINT MONO (-5765 3410);
DISPLAY INVISIBLE (-5765 3410);
FORCEPROP 1 LASTPIN (-5775 3400) BN 13
J 2
(-5763 3408);
DISPLAY 0.617021 (-5763 3408);
PAINT PINK (-5763 3408);
FORCEPROP 1 LAST PATH I16
J 2
(-5823 3400);
DISPLAY 0.872340 (-5823 3400);
PAINT GREEN (-5823 3400);
DISPLAY INVISIBLE (-5823 3400);
FORCEPROP 1 LAST HDL_TAP TRUE
J 2
(-6150 3275);
DISPLAY 1.446809 (-6150 3275);
PAINT GREEN (-6150 3275);
DISPLAY INVISIBLE (-6150 3275);
FORCEPROP 1 LAST BODY_TYPE PLUMBING
J 2
(-5825 3450);
DISPLAY 1.446809 (-5825 3450);
PAINT GREEN (-5825 3450);
DISPLAY INVISIBLE (-5825 3450);
FORCEPROP 2 LAST CDS_LIB mstr_standard
J 0
(-5825 3400);
PAINT MONO (-5825 3400);
DISPLAY INVISIBLE (-5825 3400);
FORCEADD TAP..1
R 2
(-5825 3500);
FORCEPROP 3 LASTPIN (-5775 3500) SIG_NAME P3E_CPU0_PE1_PCH_RXP<15>
J 0
(-5765 3510);
DISPLAY 0.659574 (-5765 3510);
PAINT MONO (-5765 3510);
DISPLAY INVISIBLE (-5765 3510);
FORCEPROP 1 LASTPIN (-5775 3500) BN 15
J 2
(-5763 3508);
DISPLAY 0.617021 (-5763 3508);
PAINT PINK (-5763 3508);
FORCEPROP 1 LAST PATH I17
J 2
(-5823 3500);
DISPLAY 0.872340 (-5823 3500);
PAINT GREEN (-5823 3500);
DISPLAY INVISIBLE (-5823 3500);
FORCEPROP 1 LAST HDL_TAP TRUE
J 2
(-6150 3375);
DISPLAY 1.446809 (-6150 3375);
PAINT GREEN (-6150 3375);
DISPLAY INVISIBLE (-6150 3375);
FORCEPROP 1 LAST BODY_TYPE PLUMBING
J 2
(-5825 3550);
DISPLAY 1.446809 (-5825 3550);
PAINT GREEN (-5825 3550);
DISPLAY INVISIBLE (-5825 3550);
FORCEPROP 2 LAST CDS_LIB mstr_standard
J 0
(-5825 3500);
PAINT MONO (-5825 3500);
DISPLAY INVISIBLE (-5825 3500);
FORCEADD TAP..1
R 2
(-5825 3450);
FORCEPROP 3 LASTPIN (-5775 3450) SIG_NAME P3E_CPU0_PE1_PCH_RXP<14>
J 0
(-5765 3460);
DISPLAY 0.659574 (-5765 3460);
PAINT MONO (-5765 3460);
DISPLAY INVISIBLE (-5765 3460);
FORCEPROP 1 LASTPIN (-5775 3450) BN 14
J 2
(-5763 3458);
DISPLAY 0.617021 (-5763 3458);
PAINT PINK (-5763 3458);
FORCEPROP 1 LAST PATH I18
J 2
(-5823 3450);
DISPLAY 0.872340 (-5823 3450);
PAINT GREEN (-5823 3450);
DISPLAY INVISIBLE (-5823 3450);
FORCEPROP 1 LAST HDL_TAP TRUE
J 2
(-6150 3325);
DISPLAY 1.446809 (-6150 3325);
PAINT GREEN (-6150 3325);
DISPLAY INVISIBLE (-6150 3325);
FORCEPROP 1 LAST BODY_TYPE PLUMBING
J 2
(-5825 3500);
DISPLAY 1.446809 (-5825 3500);
PAINT GREEN (-5825 3500);
DISPLAY INVISIBLE (-5825 3500);
FORCEPROP 2 LAST CDS_LIB mstr_standard
J 0
(-5825 3450);
PAINT MONO (-5825 3450);
DISPLAY INVISIBLE (-5825 3450);
FORCEADD TAP..1
R 2
(-5550 1650);
FORCEPROP 3 LASTPIN (-5500 1650) SIG_NAME P3E_CPU0_PE1_SS_RXN<1>
J 0
(-5490 1660);
DISPLAY 0.659574 (-5490 1660);
PAINT MONO (-5490 1660);
DISPLAY INVISIBLE (-5490 1660);
FORCEPROP 1 LASTPIN (-5500 1650) BN 1
J 2
(-5488 1658);
DISPLAY 0.617021 (-5488 1658);
PAINT PINK (-5488 1658);
FORCEPROP 1 LAST PATH I19
J 2
(-5548 1650);
DISPLAY 0.872340 (-5548 1650);
PAINT GREEN (-5548 1650);
DISPLAY INVISIBLE (-5548 1650);
FORCEPROP 1 LAST HDL_TAP TRUE
J 2
(-5875 1525);
DISPLAY 1.446809 (-5875 1525);
PAINT GREEN (-5875 1525);
DISPLAY INVISIBLE (-5875 1525);
FORCEPROP 1 LAST BODY_TYPE PLUMBING
J 2
(-5550 1700);
DISPLAY 1.446809 (-5550 1700);
PAINT GREEN (-5550 1700);
DISPLAY INVISIBLE (-5550 1700);
FORCEPROP 2 LAST CDS_LIB mstr_standard
J 0
(-5550 1650);
PAINT MONO (-5550 1650);
DISPLAY INVISIBLE (-5550 1650);
FORCEADD TAP..1
R 2
(-5825 1850);
FORCEPROP 3 LASTPIN (-5775 1850) SIG_NAME P3E_CPU0_PE1_SS_RXP<0>
J 0
(-5765 1860);
DISPLAY 0.659574 (-5765 1860);
PAINT MONO (-5765 1860);
DISPLAY INVISIBLE (-5765 1860);
FORCEPROP 1 LASTPIN (-5775 1850) BN 0
J 2
(-5763 1858);
DISPLAY 0.617021 (-5763 1858);
PAINT PINK (-5763 1858);
FORCEPROP 1 LAST PATH I2
J 2
(-5823 1850);
DISPLAY 0.872340 (-5823 1850);
PAINT GREEN (-5823 1850);
DISPLAY INVISIBLE (-5823 1850);
FORCEPROP 1 LAST HDL_TAP TRUE
J 2
(-6150 1725);
DISPLAY 1.446809 (-6150 1725);
PAINT GREEN (-6150 1725);
DISPLAY INVISIBLE (-6150 1725);
FORCEPROP 1 LAST BODY_TYPE PLUMBING
J 2
(-5825 1900);
DISPLAY 1.446809 (-5825 1900);
PAINT GREEN (-5825 1900);
DISPLAY INVISIBLE (-5825 1900);
FORCEPROP 2 LAST CDS_LIB mstr_standard
J 0
(-5825 1850);
PAINT MONO (-5825 1850);
DISPLAY INVISIBLE (-5825 1850);
FORCEADD TAP..1
R 2
(-5550 1600);
FORCEPROP 3 LASTPIN (-5500 1600) SIG_NAME P3E_CPU0_PE1_SS_RXN<0>
J 0
(-5490 1610);
DISPLAY 0.659574 (-5490 1610);
PAINT MONO (-5490 1610);
DISPLAY INVISIBLE (-5490 1610);
FORCEPROP 1 LASTPIN (-5500 1600) BN 0
J 2
(-5488 1608);
DISPLAY 0.617021 (-5488 1608);
PAINT PINK (-5488 1608);
FORCEPROP 1 LAST PATH I20
J 2
(-5548 1600);
DISPLAY 0.872340 (-5548 1600);
PAINT GREEN (-5548 1600);
DISPLAY INVISIBLE (-5548 1600);
FORCEPROP 1 LAST HDL_TAP TRUE
J 2
(-5875 1475);
DISPLAY 1.446809 (-5875 1475);
PAINT GREEN (-5875 1475);
DISPLAY INVISIBLE (-5875 1475);
FORCEPROP 1 LAST BODY_TYPE PLUMBING
J 2
(-5550 1650);
DISPLAY 1.446809 (-5550 1650);
PAINT GREEN (-5550 1650);
DISPLAY INVISIBLE (-5550 1650);
FORCEPROP 2 LAST CDS_LIB mstr_standard
J 0
(-5550 1600);
PAINT MONO (-5550 1600);
DISPLAY INVISIBLE (-5550 1600);
FORCEADD TAP..1
R 2
(-5550 1750);
FORCEPROP 3 LASTPIN (-5500 1750) SIG_NAME P3E_CPU0_PE1_SS_RXN<3>
J 0
(-5490 1760);
DISPLAY 0.659574 (-5490 1760);
PAINT MONO (-5490 1760);
DISPLAY INVISIBLE (-5490 1760);
FORCEPROP 1 LASTPIN (-5500 1750) BN 3
J 2
(-5488 1758);
DISPLAY 0.617021 (-5488 1758);
PAINT PINK (-5488 1758);
FORCEPROP 1 LAST PATH I21
J 2
(-5548 1750);
DISPLAY 0.872340 (-5548 1750);
PAINT GREEN (-5548 1750);
DISPLAY INVISIBLE (-5548 1750);
FORCEPROP 1 LAST HDL_TAP TRUE
J 2
(-5875 1625);
DISPLAY 1.446809 (-5875 1625);
PAINT GREEN (-5875 1625);
DISPLAY INVISIBLE (-5875 1625);
FORCEPROP 1 LAST BODY_TYPE PLUMBING
J 2
(-5550 1800);
DISPLAY 1.446809 (-5550 1800);
PAINT GREEN (-5550 1800);
DISPLAY INVISIBLE (-5550 1800);
FORCEPROP 2 LAST CDS_LIB mstr_standard
J 0
(-5550 1750);
PAINT MONO (-5550 1750);
DISPLAY INVISIBLE (-5550 1750);
FORCEADD TAP..1
R 2
(-5550 1700);
FORCEPROP 3 LASTPIN (-5500 1700) SIG_NAME P3E_CPU0_PE1_SS_RXN<2>
J 0
(-5490 1710);
DISPLAY 0.659574 (-5490 1710);
PAINT MONO (-5490 1710);
DISPLAY INVISIBLE (-5490 1710);
FORCEPROP 1 LASTPIN (-5500 1700) BN 2
J 2
(-5488 1708);
DISPLAY 0.617021 (-5488 1708);
PAINT PINK (-5488 1708);
FORCEPROP 1 LAST PATH I22
J 2
(-5548 1700);
DISPLAY 0.872340 (-5548 1700);
PAINT GREEN (-5548 1700);
DISPLAY INVISIBLE (-5548 1700);
FORCEPROP 1 LAST HDL_TAP TRUE
J 2
(-5875 1575);
DISPLAY 1.446809 (-5875 1575);
PAINT GREEN (-5875 1575);
DISPLAY INVISIBLE (-5875 1575);
FORCEPROP 1 LAST BODY_TYPE PLUMBING
J 2
(-5550 1750);
DISPLAY 1.446809 (-5550 1750);
PAINT GREEN (-5550 1750);
DISPLAY INVISIBLE (-5550 1750);
FORCEPROP 2 LAST CDS_LIB mstr_standard
J 0
(-5550 1700);
PAINT MONO (-5550 1700);
DISPLAY INVISIBLE (-5550 1700);
FORCEADD TAP..1
R 2
(-5550 2150);
FORCEPROP 3 LASTPIN (-5500 2150) SIG_NAME P3E_CPU0_PE1_SS_RXN<5>
J 0
(-5490 2160);
DISPLAY 0.659574 (-5490 2160);
PAINT MONO (-5490 2160);
DISPLAY INVISIBLE (-5490 2160);
FORCEPROP 1 LASTPIN (-5500 2150) BN 5
J 2
(-5488 2158);
DISPLAY 0.617021 (-5488 2158);
PAINT PINK (-5488 2158);
FORCEPROP 1 LAST PATH I24
J 2
(-5548 2150);
DISPLAY 0.872340 (-5548 2150);
PAINT GREEN (-5548 2150);
DISPLAY INVISIBLE (-5548 2150);
FORCEPROP 1 LAST HDL_TAP TRUE
J 2
(-5875 2025);
DISPLAY 1.446809 (-5875 2025);
PAINT GREEN (-5875 2025);
DISPLAY INVISIBLE (-5875 2025);
FORCEPROP 1 LAST BODY_TYPE PLUMBING
J 2
(-5550 2200);
DISPLAY 1.446809 (-5550 2200);
PAINT GREEN (-5550 2200);
DISPLAY INVISIBLE (-5550 2200);
FORCEPROP 2 LAST CDS_LIB mstr_standard
J 0
(-5550 2150);
PAINT MONO (-5550 2150);
DISPLAY INVISIBLE (-5550 2150);
FORCEADD TAP..1
R 2
(-5550 2200);
FORCEPROP 3 LASTPIN (-5500 2200) SIG_NAME P3E_CPU0_PE1_SS_RXN<6>
J 0
(-5490 2210);
DISPLAY 0.659574 (-5490 2210);
PAINT MONO (-5490 2210);
DISPLAY INVISIBLE (-5490 2210);
FORCEPROP 1 LASTPIN (-5500 2200) BN 6
J 2
(-5488 2208);
DISPLAY 0.617021 (-5488 2208);
PAINT PINK (-5488 2208);
FORCEPROP 1 LAST PATH I25
J 2
(-5548 2200);
DISPLAY 0.872340 (-5548 2200);
PAINT GREEN (-5548 2200);
DISPLAY INVISIBLE (-5548 2200);
FORCEPROP 1 LAST HDL_TAP TRUE
J 2
(-5875 2075);
DISPLAY 1.446809 (-5875 2075);
PAINT GREEN (-5875 2075);
DISPLAY INVISIBLE (-5875 2075);
FORCEPROP 1 LAST BODY_TYPE PLUMBING
J 2
(-5550 2250);
DISPLAY 1.446809 (-5550 2250);
PAINT GREEN (-5550 2250);
DISPLAY INVISIBLE (-5550 2250);
FORCEPROP 2 LAST CDS_LIB mstr_standard
J 0
(-5550 2200);
PAINT MONO (-5550 2200);
DISPLAY INVISIBLE (-5550 2200);
FORCEADD TAP..1
R 2
(-5550 2100);
FORCEPROP 3 LASTPIN (-5500 2100) SIG_NAME P3E_CPU0_PE1_SS_RXN<4>
J 0
(-5490 2110);
DISPLAY 0.659574 (-5490 2110);
PAINT MONO (-5490 2110);
DISPLAY INVISIBLE (-5490 2110);
FORCEPROP 1 LASTPIN (-5500 2100) BN 4
J 2
(-5488 2108);
DISPLAY 0.617021 (-5488 2108);
PAINT PINK (-5488 2108);
FORCEPROP 1 LAST PATH I26
J 2
(-5548 2100);
DISPLAY 0.872340 (-5548 2100);
PAINT GREEN (-5548 2100);
DISPLAY INVISIBLE (-5548 2100);
FORCEPROP 1 LAST HDL_TAP TRUE
J 2
(-5875 1975);
DISPLAY 1.446809 (-5875 1975);
PAINT GREEN (-5875 1975);
DISPLAY INVISIBLE (-5875 1975);
FORCEPROP 1 LAST BODY_TYPE PLUMBING
J 2
(-5550 2150);
DISPLAY 1.446809 (-5550 2150);
PAINT GREEN (-5550 2150);
DISPLAY INVISIBLE (-5550 2150);
FORCEPROP 2 LAST CDS_LIB mstr_standard
J 0
(-5550 2100);
PAINT MONO (-5550 2100);
DISPLAY INVISIBLE (-5550 2100);
FORCEADD TAP..1
R 2
(-5550 2250);
FORCEPROP 3 LASTPIN (-5500 2250) SIG_NAME P3E_CPU0_PE1_SS_RXN<7>
J 0
(-5490 2260);
DISPLAY 0.659574 (-5490 2260);
PAINT MONO (-5490 2260);
DISPLAY INVISIBLE (-5490 2260);
FORCEPROP 1 LASTPIN (-5500 2250) BN 7
J 2
(-5488 2258);
DISPLAY 0.617021 (-5488 2258);
PAINT PINK (-5488 2258);
FORCEPROP 1 LAST PATH I27
J 2
(-5548 2250);
DISPLAY 0.872340 (-5548 2250);
PAINT GREEN (-5548 2250);
DISPLAY INVISIBLE (-5548 2250);
FORCEPROP 1 LAST HDL_TAP TRUE
J 2
(-5875 2125);
DISPLAY 1.446809 (-5875 2125);
PAINT GREEN (-5875 2125);
DISPLAY INVISIBLE (-5875 2125);
FORCEPROP 1 LAST BODY_TYPE PLUMBING
J 2
(-5550 2300);
DISPLAY 1.446809 (-5550 2300);
PAINT GREEN (-5550 2300);
DISPLAY INVISIBLE (-5550 2300);
FORCEPROP 2 LAST CDS_LIB mstr_standard
J 0
(-5550 2250);
PAINT MONO (-5550 2250);
DISPLAY INVISIBLE (-5550 2250);
FORCEADD TAP..1
R 2
(-5550 2600);
FORCEPROP 3 LASTPIN (-5500 2600) SIG_NAME P3E_CPU0_PE1_PCH_RXN<8>
J 0
(-5490 2610);
DISPLAY 0.659574 (-5490 2610);
PAINT MONO (-5490 2610);
DISPLAY INVISIBLE (-5490 2610);
FORCEPROP 1 LASTPIN (-5500 2600) BN 8
J 2
(-5488 2608);
DISPLAY 0.617021 (-5488 2608);
PAINT PINK (-5488 2608);
FORCEPROP 1 LAST PATH I28
J 2
(-5548 2600);
DISPLAY 0.872340 (-5548 2600);
PAINT GREEN (-5548 2600);
DISPLAY INVISIBLE (-5548 2600);
FORCEPROP 1 LAST HDL_TAP TRUE
J 2
(-5875 2475);
DISPLAY 1.446809 (-5875 2475);
PAINT GREEN (-5875 2475);
DISPLAY INVISIBLE (-5875 2475);
FORCEPROP 1 LAST BODY_TYPE PLUMBING
J 2
(-5550 2650);
DISPLAY 1.446809 (-5550 2650);
PAINT GREEN (-5550 2650);
DISPLAY INVISIBLE (-5550 2650);
FORCEPROP 2 LAST CDS_LIB mstr_standard
J 0
(-5550 2600);
PAINT MONO (-5550 2600);
DISPLAY INVISIBLE (-5550 2600);
FORCEADD TAP..1
R 2
(-5550 2650);
FORCEPROP 3 LASTPIN (-5500 2650) SIG_NAME P3E_CPU0_PE1_PCH_RXN<9>
J 0
(-5490 2660);
DISPLAY 0.659574 (-5490 2660);
PAINT MONO (-5490 2660);
DISPLAY INVISIBLE (-5490 2660);
FORCEPROP 1 LASTPIN (-5500 2650) BN 9
J 2
(-5488 2658);
DISPLAY 0.617021 (-5488 2658);
PAINT PINK (-5488 2658);
FORCEPROP 1 LAST PATH I29
J 2
(-5548 2650);
DISPLAY 0.872340 (-5548 2650);
PAINT GREEN (-5548 2650);
DISPLAY INVISIBLE (-5548 2650);
FORCEPROP 1 LAST HDL_TAP TRUE
J 2
(-5875 2525);
DISPLAY 1.446809 (-5875 2525);
PAINT GREEN (-5875 2525);
DISPLAY INVISIBLE (-5875 2525);
FORCEPROP 1 LAST BODY_TYPE PLUMBING
J 2
(-5550 2700);
DISPLAY 1.446809 (-5550 2700);
PAINT GREEN (-5550 2700);
DISPLAY INVISIBLE (-5550 2700);
FORCEPROP 2 LAST CDS_LIB mstr_standard
J 0
(-5550 2650);
PAINT MONO (-5550 2650);
DISPLAY INVISIBLE (-5550 2650);
FORCEADD TAP..1
R 2
(-5825 1950);
FORCEPROP 3 LASTPIN (-5775 1950) SIG_NAME P3E_CPU0_PE1_SS_RXP<2>
J 0
(-5765 1960);
DISPLAY 0.659574 (-5765 1960);
PAINT MONO (-5765 1960);
DISPLAY INVISIBLE (-5765 1960);
FORCEPROP 1 LASTPIN (-5775 1950) BN 2
J 2
(-5763 1958);
DISPLAY 0.617021 (-5763 1958);
PAINT PINK (-5763 1958);
FORCEPROP 1 LAST PATH I3
J 2
(-5823 1950);
DISPLAY 0.872340 (-5823 1950);
PAINT GREEN (-5823 1950);
DISPLAY INVISIBLE (-5823 1950);
FORCEPROP 1 LAST HDL_TAP TRUE
J 2
(-6150 1825);
DISPLAY 1.446809 (-6150 1825);
PAINT GREEN (-6150 1825);
DISPLAY INVISIBLE (-6150 1825);
FORCEPROP 1 LAST BODY_TYPE PLUMBING
J 2
(-5825 2000);
DISPLAY 1.446809 (-5825 2000);
PAINT GREEN (-5825 2000);
DISPLAY INVISIBLE (-5825 2000);
FORCEPROP 2 LAST CDS_LIB mstr_standard
J 0
(-5825 1950);
PAINT MONO (-5825 1950);
DISPLAY INVISIBLE (-5825 1950);
FORCEADD TAP..1
R 2
(-5550 2700);
FORCEPROP 3 LASTPIN (-5500 2700) SIG_NAME P3E_CPU0_PE1_PCH_RXN<10>
J 0
(-5490 2710);
DISPLAY 0.659574 (-5490 2710);
PAINT MONO (-5490 2710);
DISPLAY INVISIBLE (-5490 2710);
FORCEPROP 1 LASTPIN (-5500 2700) BN 10
J 2
(-5488 2708);
DISPLAY 0.617021 (-5488 2708);
PAINT PINK (-5488 2708);
FORCEPROP 1 LAST PATH I30
J 2
(-5548 2700);
DISPLAY 0.872340 (-5548 2700);
PAINT GREEN (-5548 2700);
DISPLAY INVISIBLE (-5548 2700);
FORCEPROP 1 LAST HDL_TAP TRUE
J 2
(-5875 2575);
DISPLAY 1.446809 (-5875 2575);
PAINT GREEN (-5875 2575);
DISPLAY INVISIBLE (-5875 2575);
FORCEPROP 1 LAST BODY_TYPE PLUMBING
J 2
(-5550 2750);
DISPLAY 1.446809 (-5550 2750);
PAINT GREEN (-5550 2750);
DISPLAY INVISIBLE (-5550 2750);
FORCEPROP 2 LAST CDS_LIB mstr_standard
J 0
(-5550 2700);
PAINT MONO (-5550 2700);
DISPLAY INVISIBLE (-5550 2700);
FORCEADD TAP..1
R 2
(-5550 2750);
FORCEPROP 3 LASTPIN (-5500 2750) SIG_NAME P3E_CPU0_PE1_PCH_RXN<11>
J 0
(-5490 2760);
DISPLAY 0.659574 (-5490 2760);
PAINT MONO (-5490 2760);
DISPLAY INVISIBLE (-5490 2760);
FORCEPROP 1 LASTPIN (-5500 2750) BN 11
J 2
(-5488 2758);
DISPLAY 0.617021 (-5488 2758);
PAINT PINK (-5488 2758);
FORCEPROP 1 LAST PATH I31
J 2
(-5548 2750);
DISPLAY 0.872340 (-5548 2750);
PAINT GREEN (-5548 2750);
DISPLAY INVISIBLE (-5548 2750);
FORCEPROP 1 LAST HDL_TAP TRUE
J 2
(-5875 2625);
DISPLAY 1.446809 (-5875 2625);
PAINT GREEN (-5875 2625);
DISPLAY INVISIBLE (-5875 2625);
FORCEPROP 1 LAST BODY_TYPE PLUMBING
J 2
(-5550 2800);
DISPLAY 1.446809 (-5550 2800);
PAINT GREEN (-5550 2800);
DISPLAY INVISIBLE (-5550 2800);
FORCEPROP 2 LAST CDS_LIB mstr_standard
J 0
(-5550 2750);
PAINT MONO (-5550 2750);
DISPLAY INVISIBLE (-5550 2750);
FORCEADD TAP..1
R 2
(-5550 3150);
FORCEPROP 3 LASTPIN (-5500 3150) SIG_NAME P3E_CPU0_PE1_PCH_RXN<13>
J 0
(-5490 3160);
DISPLAY 0.659574 (-5490 3160);
PAINT MONO (-5490 3160);
DISPLAY INVISIBLE (-5490 3160);
FORCEPROP 1 LASTPIN (-5500 3150) BN 13
J 2
(-5488 3158);
DISPLAY 0.617021 (-5488 3158);
PAINT PINK (-5488 3158);
FORCEPROP 1 LAST PATH I32
J 2
(-5548 3150);
DISPLAY 0.872340 (-5548 3150);
PAINT GREEN (-5548 3150);
DISPLAY INVISIBLE (-5548 3150);
FORCEPROP 1 LAST HDL_TAP TRUE
J 2
(-5875 3025);
DISPLAY 1.446809 (-5875 3025);
PAINT GREEN (-5875 3025);
DISPLAY INVISIBLE (-5875 3025);
FORCEPROP 1 LAST BODY_TYPE PLUMBING
J 2
(-5550 3200);
DISPLAY 1.446809 (-5550 3200);
PAINT GREEN (-5550 3200);
DISPLAY INVISIBLE (-5550 3200);
FORCEPROP 2 LAST CDS_LIB mstr_standard
J 0
(-5550 3150);
PAINT MONO (-5550 3150);
DISPLAY INVISIBLE (-5550 3150);
FORCEADD TAP..1
R 2
(-5550 3100);
FORCEPROP 3 LASTPIN (-5500 3100) SIG_NAME P3E_CPU0_PE1_PCH_RXN<12>
J 0
(-5490 3110);
DISPLAY 0.659574 (-5490 3110);
PAINT MONO (-5490 3110);
DISPLAY INVISIBLE (-5490 3110);
FORCEPROP 1 LASTPIN (-5500 3100) BN 12
J 2
(-5488 3108);
DISPLAY 0.617021 (-5488 3108);
PAINT PINK (-5488 3108);
FORCEPROP 1 LAST PATH I33
J 2
(-5548 3100);
DISPLAY 0.872340 (-5548 3100);
PAINT GREEN (-5548 3100);
DISPLAY INVISIBLE (-5548 3100);
FORCEPROP 1 LAST HDL_TAP TRUE
J 2
(-5875 2975);
DISPLAY 1.446809 (-5875 2975);
PAINT GREEN (-5875 2975);
DISPLAY INVISIBLE (-5875 2975);
FORCEPROP 1 LAST BODY_TYPE PLUMBING
J 2
(-5550 3150);
DISPLAY 1.446809 (-5550 3150);
PAINT GREEN (-5550 3150);
DISPLAY INVISIBLE (-5550 3150);
FORCEPROP 2 LAST CDS_LIB mstr_standard
J 0
(-5550 3100);
PAINT MONO (-5550 3100);
DISPLAY INVISIBLE (-5550 3100);
FORCEADD TAP..1
R 2
(-5550 3200);
FORCEPROP 3 LASTPIN (-5500 3200) SIG_NAME P3E_CPU0_PE1_PCH_RXN<14>
J 0
(-5490 3210);
DISPLAY 0.659574 (-5490 3210);
PAINT MONO (-5490 3210);
DISPLAY INVISIBLE (-5490 3210);
FORCEPROP 1 LASTPIN (-5500 3200) BN 14
J 2
(-5488 3208);
DISPLAY 0.617021 (-5488 3208);
PAINT PINK (-5488 3208);
FORCEPROP 1 LAST PATH I34
J 2
(-5548 3200);
DISPLAY 0.872340 (-5548 3200);
PAINT GREEN (-5548 3200);
DISPLAY INVISIBLE (-5548 3200);
FORCEPROP 1 LAST HDL_TAP TRUE
J 2
(-5875 3075);
DISPLAY 1.446809 (-5875 3075);
PAINT GREEN (-5875 3075);
DISPLAY INVISIBLE (-5875 3075);
FORCEPROP 1 LAST BODY_TYPE PLUMBING
J 2
(-5550 3250);
DISPLAY 1.446809 (-5550 3250);
PAINT GREEN (-5550 3250);
DISPLAY INVISIBLE (-5550 3250);
FORCEPROP 2 LAST CDS_LIB mstr_standard
J 0
(-5550 3200);
PAINT MONO (-5550 3200);
DISPLAY INVISIBLE (-5550 3200);
FORCEADD TAP..1
R 2
(-5550 3250);
FORCEPROP 3 LASTPIN (-5500 3250) SIG_NAME P3E_CPU0_PE1_PCH_RXN<15>
J 0
(-5490 3260);
DISPLAY 0.659574 (-5490 3260);
PAINT MONO (-5490 3260);
DISPLAY INVISIBLE (-5490 3260);
FORCEPROP 1 LASTPIN (-5500 3250) BN 15
J 2
(-5488 3258);
DISPLAY 0.617021 (-5488 3258);
PAINT PINK (-5488 3258);
FORCEPROP 1 LAST PATH I35
J 2
(-5548 3250);
DISPLAY 0.872340 (-5548 3250);
PAINT GREEN (-5548 3250);
DISPLAY INVISIBLE (-5548 3250);
FORCEPROP 1 LAST HDL_TAP TRUE
J 2
(-5875 3125);
DISPLAY 1.446809 (-5875 3125);
PAINT GREEN (-5875 3125);
DISPLAY INVISIBLE (-5875 3125);
FORCEPROP 1 LAST BODY_TYPE PLUMBING
J 2
(-5550 3300);
DISPLAY 1.446809 (-5550 3300);
PAINT GREEN (-5550 3300);
DISPLAY INVISIBLE (-5550 3300);
FORCEPROP 2 LAST CDS_LIB mstr_standard
J 0
(-5550 3250);
PAINT MONO (-5550 3250);
DISPLAY INVISIBLE (-5550 3250);
FORCEADD TAP..1
(-2625 1600);
FORCEPROP 3 LASTPIN (-2675 1600) SIG_NAME P3E_CPU0_PE1_SS_TXN<0>
J 0
(-2665 1610);
DISPLAY 0.659574 (-2665 1610);
PAINT MONO (-2665 1610);
DISPLAY INVISIBLE (-2665 1610);
FORCEPROP 1 LASTPIN (-2675 1600) BN 0
J 0
(-2687 1608);
DISPLAY 0.617021 (-2687 1608);
PAINT PINK (-2687 1608);
FORCEPROP 1 LAST PATH I36
J 0
(-2627 1600);
DISPLAY 0.872340 (-2627 1600);
PAINT GREEN (-2627 1600);
DISPLAY INVISIBLE (-2627 1600);
FORCEPROP 1 LAST HDL_TAP TRUE
J 0
(-2300 1475);
DISPLAY 1.446809 (-2300 1475);
PAINT GREEN (-2300 1475);
DISPLAY INVISIBLE (-2300 1475);
FORCEPROP 1 LAST BODY_TYPE PLUMBING
J 0
(-2625 1650);
DISPLAY 1.446809 (-2625 1650);
PAINT GREEN (-2625 1650);
DISPLAY INVISIBLE (-2625 1650);
FORCEPROP 2 LAST CDS_LIB mstr_standard
J 2
(-2625 1600);
PAINT MONO (-2625 1600);
DISPLAY INVISIBLE (-2625 1600);
FORCEADD TAP..1
(-2625 1650);
FORCEPROP 3 LASTPIN (-2675 1650) SIG_NAME P3E_CPU0_PE1_SS_TXN<1>
J 0
(-2665 1660);
DISPLAY 0.659574 (-2665 1660);
PAINT MONO (-2665 1660);
DISPLAY INVISIBLE (-2665 1660);
FORCEPROP 1 LASTPIN (-2675 1650) BN 1
J 0
(-2687 1658);
DISPLAY 0.617021 (-2687 1658);
PAINT PINK (-2687 1658);
FORCEPROP 1 LAST PATH I37
J 0
(-2627 1650);
DISPLAY 0.872340 (-2627 1650);
PAINT GREEN (-2627 1650);
DISPLAY INVISIBLE (-2627 1650);
FORCEPROP 1 LAST HDL_TAP TRUE
J 0
(-2300 1525);
DISPLAY 1.446809 (-2300 1525);
PAINT GREEN (-2300 1525);
DISPLAY INVISIBLE (-2300 1525);
FORCEPROP 1 LAST BODY_TYPE PLUMBING
J 0
(-2625 1700);
DISPLAY 1.446809 (-2625 1700);
PAINT GREEN (-2625 1700);
DISPLAY INVISIBLE (-2625 1700);
FORCEPROP 2 LAST CDS_LIB mstr_standard
J 2
(-2625 1650);
PAINT MONO (-2625 1650);
DISPLAY INVISIBLE (-2625 1650);
FORCEADD TAP..1
(-2625 1700);
FORCEPROP 3 LASTPIN (-2675 1700) SIG_NAME P3E_CPU0_PE1_SS_TXN<2>
J 0
(-2665 1710);
DISPLAY 0.659574 (-2665 1710);
PAINT MONO (-2665 1710);
DISPLAY INVISIBLE (-2665 1710);
FORCEPROP 1 LASTPIN (-2675 1700) BN 2
J 0
(-2687 1708);
DISPLAY 0.617021 (-2687 1708);
PAINT PINK (-2687 1708);
FORCEPROP 1 LAST PATH I38
J 0
(-2627 1700);
DISPLAY 0.872340 (-2627 1700);
PAINT GREEN (-2627 1700);
DISPLAY INVISIBLE (-2627 1700);
FORCEPROP 1 LAST HDL_TAP TRUE
J 0
(-2300 1575);
DISPLAY 1.446809 (-2300 1575);
PAINT GREEN (-2300 1575);
DISPLAY INVISIBLE (-2300 1575);
FORCEPROP 1 LAST BODY_TYPE PLUMBING
J 0
(-2625 1750);
DISPLAY 1.446809 (-2625 1750);
PAINT GREEN (-2625 1750);
DISPLAY INVISIBLE (-2625 1750);
FORCEPROP 2 LAST CDS_LIB mstr_standard
J 2
(-2625 1700);
PAINT MONO (-2625 1700);
DISPLAY INVISIBLE (-2625 1700);
FORCEADD TAP..1
(-2625 1750);
FORCEPROP 3 LASTPIN (-2675 1750) SIG_NAME P3E_CPU0_PE1_SS_TXN<3>
J 0
(-2665 1760);
DISPLAY 0.659574 (-2665 1760);
PAINT MONO (-2665 1760);
DISPLAY INVISIBLE (-2665 1760);
FORCEPROP 1 LASTPIN (-2675 1750) BN 3
J 0
(-2687 1758);
DISPLAY 0.617021 (-2687 1758);
PAINT PINK (-2687 1758);
FORCEPROP 1 LAST PATH I39
J 0
(-2627 1750);
DISPLAY 0.872340 (-2627 1750);
PAINT GREEN (-2627 1750);
DISPLAY INVISIBLE (-2627 1750);
FORCEPROP 1 LAST HDL_TAP TRUE
J 0
(-2300 1625);
DISPLAY 1.446809 (-2300 1625);
PAINT GREEN (-2300 1625);
DISPLAY INVISIBLE (-2300 1625);
FORCEPROP 1 LAST BODY_TYPE PLUMBING
J 0
(-2625 1800);
DISPLAY 1.446809 (-2625 1800);
PAINT GREEN (-2625 1800);
DISPLAY INVISIBLE (-2625 1800);
FORCEPROP 2 LAST CDS_LIB mstr_standard
J 2
(-2625 1750);
PAINT MONO (-2625 1750);
DISPLAY INVISIBLE (-2625 1750);
FORCEADD TAP..1
(-2175 1850);
FORCEPROP 3 LASTPIN (-2225 1850) SIG_NAME P3E_CPU0_PE1_SS_TXP<0>
J 0
(-2215 1860);
DISPLAY 0.659574 (-2215 1860);
PAINT MONO (-2215 1860);
DISPLAY INVISIBLE (-2215 1860);
FORCEPROP 1 LASTPIN (-2225 1850) BN 0
J 0
(-2237 1858);
DISPLAY 0.617021 (-2237 1858);
PAINT PINK (-2237 1858);
FORCEPROP 1 LAST PATH I40
J 0
(-2177 1850);
DISPLAY 0.872340 (-2177 1850);
PAINT GREEN (-2177 1850);
DISPLAY INVISIBLE (-2177 1850);
FORCEPROP 1 LAST HDL_TAP TRUE
J 0
(-1850 1725);
DISPLAY 1.446809 (-1850 1725);
PAINT GREEN (-1850 1725);
DISPLAY INVISIBLE (-1850 1725);
FORCEPROP 1 LAST BODY_TYPE PLUMBING
J 0
(-2175 1900);
DISPLAY 1.446809 (-2175 1900);
PAINT GREEN (-2175 1900);
DISPLAY INVISIBLE (-2175 1900);
FORCEPROP 2 LAST CDS_LIB mstr_standard
J 2
(-2175 1850);
PAINT MONO (-2175 1850);
DISPLAY INVISIBLE (-2175 1850);
FORCEADD TAP..1
(-2175 1900);
FORCEPROP 3 LASTPIN (-2225 1900) SIG_NAME P3E_CPU0_PE1_SS_TXP<1>
J 0
(-2215 1910);
DISPLAY 0.659574 (-2215 1910);
PAINT MONO (-2215 1910);
DISPLAY INVISIBLE (-2215 1910);
FORCEPROP 1 LASTPIN (-2225 1900) BN 1
J 0
(-2237 1908);
DISPLAY 0.617021 (-2237 1908);
PAINT PINK (-2237 1908);
FORCEPROP 1 LAST PATH I41
J 0
(-2177 1900);
DISPLAY 0.872340 (-2177 1900);
PAINT GREEN (-2177 1900);
DISPLAY INVISIBLE (-2177 1900);
FORCEPROP 1 LAST HDL_TAP TRUE
J 0
(-1850 1775);
DISPLAY 1.446809 (-1850 1775);
PAINT GREEN (-1850 1775);
DISPLAY INVISIBLE (-1850 1775);
FORCEPROP 1 LAST BODY_TYPE PLUMBING
J 0
(-2175 1950);
DISPLAY 1.446809 (-2175 1950);
PAINT GREEN (-2175 1950);
DISPLAY INVISIBLE (-2175 1950);
FORCEPROP 2 LAST CDS_LIB mstr_standard
J 2
(-2175 1900);
PAINT MONO (-2175 1900);
DISPLAY INVISIBLE (-2175 1900);
FORCEADD TAP..1
(-2175 1950);
FORCEPROP 3 LASTPIN (-2225 1950) SIG_NAME P3E_CPU0_PE1_SS_TXP<2>
J 0
(-2215 1960);
DISPLAY 0.659574 (-2215 1960);
PAINT MONO (-2215 1960);
DISPLAY INVISIBLE (-2215 1960);
FORCEPROP 1 LASTPIN (-2225 1950) BN 2
J 0
(-2237 1958);
DISPLAY 0.617021 (-2237 1958);
PAINT PINK (-2237 1958);
FORCEPROP 1 LAST PATH I42
J 0
(-2177 1950);
DISPLAY 0.872340 (-2177 1950);
PAINT GREEN (-2177 1950);
DISPLAY INVISIBLE (-2177 1950);
FORCEPROP 1 LAST HDL_TAP TRUE
J 0
(-1850 1825);
DISPLAY 1.446809 (-1850 1825);
PAINT GREEN (-1850 1825);
DISPLAY INVISIBLE (-1850 1825);
FORCEPROP 1 LAST BODY_TYPE PLUMBING
J 0
(-2175 2000);
DISPLAY 1.446809 (-2175 2000);
PAINT GREEN (-2175 2000);
DISPLAY INVISIBLE (-2175 2000);
FORCEPROP 2 LAST CDS_LIB mstr_standard
J 2
(-2175 1950);
PAINT MONO (-2175 1950);
DISPLAY INVISIBLE (-2175 1950);
FORCEADD TAP..1
(-2625 2100);
FORCEPROP 3 LASTPIN (-2675 2100) SIG_NAME P3E_CPU0_PE1_SS_TXN<4>
J 0
(-2665 2110);
DISPLAY 0.659574 (-2665 2110);
PAINT MONO (-2665 2110);
DISPLAY INVISIBLE (-2665 2110);
FORCEPROP 1 LASTPIN (-2675 2100) BN 4
J 0
(-2687 2108);
DISPLAY 0.617021 (-2687 2108);
PAINT PINK (-2687 2108);
FORCEPROP 1 LAST PATH I43
J 0
(-2627 2100);
DISPLAY 0.872340 (-2627 2100);
PAINT GREEN (-2627 2100);
DISPLAY INVISIBLE (-2627 2100);
FORCEPROP 1 LAST HDL_TAP TRUE
J 0
(-2300 1975);
DISPLAY 1.446809 (-2300 1975);
PAINT GREEN (-2300 1975);
DISPLAY INVISIBLE (-2300 1975);
FORCEPROP 1 LAST BODY_TYPE PLUMBING
J 0
(-2625 2150);
DISPLAY 1.446809 (-2625 2150);
PAINT GREEN (-2625 2150);
DISPLAY INVISIBLE (-2625 2150);
FORCEPROP 2 LAST CDS_LIB mstr_standard
J 0
(-2625 2100);
PAINT MONO (-2625 2100);
DISPLAY INVISIBLE (-2625 2100);
FORCEADD TAP..1
(-2625 2150);
FORCEPROP 3 LASTPIN (-2675 2150) SIG_NAME P3E_CPU0_PE1_SS_TXN<5>
J 0
(-2665 2160);
DISPLAY 0.659574 (-2665 2160);
PAINT MONO (-2665 2160);
DISPLAY INVISIBLE (-2665 2160);
FORCEPROP 1 LASTPIN (-2675 2150) BN 5
J 0
(-2687 2158);
DISPLAY 0.617021 (-2687 2158);
PAINT PINK (-2687 2158);
FORCEPROP 1 LAST PATH I44
J 0
(-2627 2150);
DISPLAY 0.872340 (-2627 2150);
PAINT GREEN (-2627 2150);
DISPLAY INVISIBLE (-2627 2150);
FORCEPROP 1 LAST HDL_TAP TRUE
J 0
(-2300 2025);
DISPLAY 1.446809 (-2300 2025);
PAINT GREEN (-2300 2025);
DISPLAY INVISIBLE (-2300 2025);
FORCEPROP 1 LAST BODY_TYPE PLUMBING
J 0
(-2625 2200);
DISPLAY 1.446809 (-2625 2200);
PAINT GREEN (-2625 2200);
DISPLAY INVISIBLE (-2625 2200);
FORCEPROP 2 LAST CDS_LIB mstr_standard
J 0
(-2625 2150);
PAINT MONO (-2625 2150);
DISPLAY INVISIBLE (-2625 2150);
FORCEADD TAP..1
(-2625 2200);
FORCEPROP 3 LASTPIN (-2675 2200) SIG_NAME P3E_CPU0_PE1_SS_TXN<6>
J 0
(-2665 2210);
DISPLAY 0.659574 (-2665 2210);
PAINT MONO (-2665 2210);
DISPLAY INVISIBLE (-2665 2210);
FORCEPROP 1 LASTPIN (-2675 2200) BN 6
J 0
(-2687 2208);
DISPLAY 0.617021 (-2687 2208);
PAINT PINK (-2687 2208);
FORCEPROP 1 LAST PATH I45
J 0
(-2627 2200);
DISPLAY 0.872340 (-2627 2200);
PAINT GREEN (-2627 2200);
DISPLAY INVISIBLE (-2627 2200);
FORCEPROP 1 LAST HDL_TAP TRUE
J 0
(-2300 2075);
DISPLAY 1.446809 (-2300 2075);
PAINT GREEN (-2300 2075);
DISPLAY INVISIBLE (-2300 2075);
FORCEPROP 1 LAST BODY_TYPE PLUMBING
J 0
(-2625 2250);
DISPLAY 1.446809 (-2625 2250);
PAINT GREEN (-2625 2250);
DISPLAY INVISIBLE (-2625 2250);
FORCEPROP 2 LAST CDS_LIB mstr_standard
J 0
(-2625 2200);
PAINT MONO (-2625 2200);
DISPLAY INVISIBLE (-2625 2200);
FORCEADD TAP..1
(-2625 2250);
FORCEPROP 3 LASTPIN (-2675 2250) SIG_NAME P3E_CPU0_PE1_SS_TXN<7>
J 0
(-2665 2260);
DISPLAY 0.659574 (-2665 2260);
PAINT MONO (-2665 2260);
DISPLAY INVISIBLE (-2665 2260);
FORCEPROP 1 LASTPIN (-2675 2250) BN 7
J 0
(-2687 2258);
DISPLAY 0.617021 (-2687 2258);
PAINT PINK (-2687 2258);
FORCEPROP 1 LAST PATH I46
J 0
(-2627 2250);
DISPLAY 0.872340 (-2627 2250);
PAINT GREEN (-2627 2250);
DISPLAY INVISIBLE (-2627 2250);
FORCEPROP 1 LAST HDL_TAP TRUE
J 0
(-2300 2125);
DISPLAY 1.446809 (-2300 2125);
PAINT GREEN (-2300 2125);
DISPLAY INVISIBLE (-2300 2125);
FORCEPROP 1 LAST BODY_TYPE PLUMBING
J 0
(-2625 2300);
DISPLAY 1.446809 (-2625 2300);
PAINT GREEN (-2625 2300);
DISPLAY INVISIBLE (-2625 2300);
FORCEPROP 2 LAST CDS_LIB mstr_standard
J 0
(-2625 2250);
PAINT MONO (-2625 2250);
DISPLAY INVISIBLE (-2625 2250);
FORCEADD TAP..1
(-2625 2600);
FORCEPROP 3 LASTPIN (-2675 2600) SIG_NAME P3E_CPU0_PE1_PCH_TXN<8>
J 0
(-2665 2610);
DISPLAY 0.659574 (-2665 2610);
PAINT MONO (-2665 2610);
DISPLAY INVISIBLE (-2665 2610);
FORCEPROP 1 LASTPIN (-2675 2600) BN 8
J 0
(-2687 2608);
DISPLAY 0.617021 (-2687 2608);
PAINT PINK (-2687 2608);
FORCEPROP 1 LAST PATH I47
J 0
(-2627 2600);
DISPLAY 0.872340 (-2627 2600);
PAINT GREEN (-2627 2600);
DISPLAY INVISIBLE (-2627 2600);
FORCEPROP 1 LAST HDL_TAP TRUE
J 0
(-2300 2475);
DISPLAY 1.446809 (-2300 2475);
PAINT GREEN (-2300 2475);
DISPLAY INVISIBLE (-2300 2475);
FORCEPROP 1 LAST BODY_TYPE PLUMBING
J 0
(-2625 2650);
DISPLAY 1.446809 (-2625 2650);
PAINT GREEN (-2625 2650);
DISPLAY INVISIBLE (-2625 2650);
FORCEPROP 2 LAST CDS_LIB mstr_standard
J 2
(-2625 2600);
PAINT MONO (-2625 2600);
DISPLAY INVISIBLE (-2625 2600);
FORCEADD TAP..1
(-2625 2650);
FORCEPROP 3 LASTPIN (-2675 2650) SIG_NAME P3E_CPU0_PE1_PCH_TXN<9>
J 0
(-2665 2660);
DISPLAY 0.659574 (-2665 2660);
PAINT MONO (-2665 2660);
DISPLAY INVISIBLE (-2665 2660);
FORCEPROP 1 LASTPIN (-2675 2650) BN 9
J 0
(-2687 2658);
DISPLAY 0.617021 (-2687 2658);
PAINT PINK (-2687 2658);
FORCEPROP 1 LAST PATH I48
J 0
(-2627 2650);
DISPLAY 0.872340 (-2627 2650);
PAINT GREEN (-2627 2650);
DISPLAY INVISIBLE (-2627 2650);
FORCEPROP 1 LAST HDL_TAP TRUE
J 0
(-2300 2525);
DISPLAY 1.446809 (-2300 2525);
PAINT GREEN (-2300 2525);
DISPLAY INVISIBLE (-2300 2525);
FORCEPROP 1 LAST BODY_TYPE PLUMBING
J 0
(-2625 2700);
DISPLAY 1.446809 (-2625 2700);
PAINT GREEN (-2625 2700);
DISPLAY INVISIBLE (-2625 2700);
FORCEPROP 2 LAST CDS_LIB mstr_standard
J 2
(-2625 2650);
PAINT MONO (-2625 2650);
DISPLAY INVISIBLE (-2625 2650);
FORCEADD TAP..1
(-2625 2700);
FORCEPROP 3 LASTPIN (-2675 2700) SIG_NAME P3E_CPU0_PE1_PCH_TXN<10>
J 0
(-2665 2710);
DISPLAY 0.659574 (-2665 2710);
PAINT MONO (-2665 2710);
DISPLAY INVISIBLE (-2665 2710);
FORCEPROP 1 LASTPIN (-2675 2700) BN 10
J 0
(-2687 2708);
DISPLAY 0.617021 (-2687 2708);
PAINT PINK (-2687 2708);
FORCEPROP 1 LAST PATH I49
J 0
(-2627 2700);
DISPLAY 0.872340 (-2627 2700);
PAINT GREEN (-2627 2700);
DISPLAY INVISIBLE (-2627 2700);
FORCEPROP 1 LAST HDL_TAP TRUE
J 0
(-2300 2575);
DISPLAY 1.446809 (-2300 2575);
PAINT GREEN (-2300 2575);
DISPLAY INVISIBLE (-2300 2575);
FORCEPROP 1 LAST BODY_TYPE PLUMBING
J 0
(-2625 2750);
DISPLAY 1.446809 (-2625 2750);
PAINT GREEN (-2625 2750);
DISPLAY INVISIBLE (-2625 2750);
FORCEPROP 2 LAST CDS_LIB mstr_standard
J 2
(-2625 2700);
PAINT MONO (-2625 2700);
DISPLAY INVISIBLE (-2625 2700);
FORCEADD TAP..1
(-2175 2000);
FORCEPROP 3 LASTPIN (-2225 2000) SIG_NAME P3E_CPU0_PE1_SS_TXP<3>
J 0
(-2215 2010);
DISPLAY 0.659574 (-2215 2010);
PAINT MONO (-2215 2010);
DISPLAY INVISIBLE (-2215 2010);
FORCEPROP 1 LASTPIN (-2225 2000) BN 3
J 0
(-2237 2008);
DISPLAY 0.617021 (-2237 2008);
PAINT PINK (-2237 2008);
FORCEPROP 1 LAST PATH I51
J 0
(-2177 2000);
DISPLAY 0.872340 (-2177 2000);
PAINT GREEN (-2177 2000);
DISPLAY INVISIBLE (-2177 2000);
FORCEPROP 1 LAST HDL_TAP TRUE
J 0
(-1850 1875);
DISPLAY 1.446809 (-1850 1875);
PAINT GREEN (-1850 1875);
DISPLAY INVISIBLE (-1850 1875);
FORCEPROP 1 LAST BODY_TYPE PLUMBING
J 0
(-2175 2050);
DISPLAY 1.446809 (-2175 2050);
PAINT GREEN (-2175 2050);
DISPLAY INVISIBLE (-2175 2050);
FORCEPROP 2 LAST CDS_LIB mstr_standard
J 2
(-2175 2000);
PAINT MONO (-2175 2000);
DISPLAY INVISIBLE (-2175 2000);
FORCEADD TAP..1
(-2175 2350);
FORCEPROP 3 LASTPIN (-2225 2350) SIG_NAME P3E_CPU0_PE1_SS_TXP<4>
J 0
(-2215 2360);
DISPLAY 0.659574 (-2215 2360);
PAINT MONO (-2215 2360);
DISPLAY INVISIBLE (-2215 2360);
FORCEPROP 1 LASTPIN (-2225 2350) BN 4
J 0
(-2237 2358);
DISPLAY 0.617021 (-2237 2358);
PAINT PINK (-2237 2358);
FORCEPROP 1 LAST PATH I52
J 0
(-2177 2350);
DISPLAY 0.872340 (-2177 2350);
PAINT GREEN (-2177 2350);
DISPLAY INVISIBLE (-2177 2350);
FORCEPROP 1 LAST HDL_TAP TRUE
J 0
(-1850 2225);
DISPLAY 1.446809 (-1850 2225);
PAINT GREEN (-1850 2225);
DISPLAY INVISIBLE (-1850 2225);
FORCEPROP 1 LAST BODY_TYPE PLUMBING
J 0
(-2175 2400);
DISPLAY 1.446809 (-2175 2400);
PAINT GREEN (-2175 2400);
DISPLAY INVISIBLE (-2175 2400);
FORCEPROP 2 LAST CDS_LIB mstr_standard
J 0
(-2175 2350);
PAINT MONO (-2175 2350);
DISPLAY INVISIBLE (-2175 2350);
FORCEADD TAP..1
(-2175 2400);
FORCEPROP 3 LASTPIN (-2225 2400) SIG_NAME P3E_CPU0_PE1_SS_TXP<5>
J 0
(-2215 2410);
DISPLAY 0.659574 (-2215 2410);
PAINT MONO (-2215 2410);
DISPLAY INVISIBLE (-2215 2410);
FORCEPROP 1 LASTPIN (-2225 2400) BN 5
J 0
(-2237 2408);
DISPLAY 0.617021 (-2237 2408);
PAINT PINK (-2237 2408);
FORCEPROP 1 LAST PATH I53
J 0
(-2177 2400);
DISPLAY 0.872340 (-2177 2400);
PAINT GREEN (-2177 2400);
DISPLAY INVISIBLE (-2177 2400);
FORCEPROP 1 LAST HDL_TAP TRUE
J 0
(-1850 2275);
DISPLAY 1.446809 (-1850 2275);
PAINT GREEN (-1850 2275);
DISPLAY INVISIBLE (-1850 2275);
FORCEPROP 1 LAST BODY_TYPE PLUMBING
J 0
(-2175 2450);
DISPLAY 1.446809 (-2175 2450);
PAINT GREEN (-2175 2450);
DISPLAY INVISIBLE (-2175 2450);
FORCEPROP 2 LAST CDS_LIB mstr_standard
J 0
(-2175 2400);
PAINT MONO (-2175 2400);
DISPLAY INVISIBLE (-2175 2400);
FORCEADD TAP..1
(-2175 2450);
FORCEPROP 3 LASTPIN (-2225 2450) SIG_NAME P3E_CPU0_PE1_SS_TXP<6>
J 0
(-2215 2460);
DISPLAY 0.659574 (-2215 2460);
PAINT MONO (-2215 2460);
DISPLAY INVISIBLE (-2215 2460);
FORCEPROP 1 LASTPIN (-2225 2450) BN 6
J 0
(-2237 2458);
DISPLAY 0.617021 (-2237 2458);
PAINT PINK (-2237 2458);
FORCEPROP 1 LAST PATH I54
J 0
(-2177 2450);
DISPLAY 0.872340 (-2177 2450);
PAINT GREEN (-2177 2450);
DISPLAY INVISIBLE (-2177 2450);
FORCEPROP 1 LAST HDL_TAP TRUE
J 0
(-1850 2325);
DISPLAY 1.446809 (-1850 2325);
PAINT GREEN (-1850 2325);
DISPLAY INVISIBLE (-1850 2325);
FORCEPROP 1 LAST BODY_TYPE PLUMBING
J 0
(-2175 2500);
DISPLAY 1.446809 (-2175 2500);
PAINT GREEN (-2175 2500);
DISPLAY INVISIBLE (-2175 2500);
FORCEPROP 2 LAST CDS_LIB mstr_standard
J 0
(-2175 2450);
PAINT MONO (-2175 2450);
DISPLAY INVISIBLE (-2175 2450);
FORCEADD TAP..1
(-2175 2500);
FORCEPROP 3 LASTPIN (-2225 2500) SIG_NAME P3E_CPU0_PE1_SS_TXP<7>
J 0
(-2215 2510);
DISPLAY 0.659574 (-2215 2510);
PAINT MONO (-2215 2510);
DISPLAY INVISIBLE (-2215 2510);
FORCEPROP 1 LASTPIN (-2225 2500) BN 7
J 0
(-2237 2508);
DISPLAY 0.617021 (-2237 2508);
PAINT PINK (-2237 2508);
FORCEPROP 1 LAST PATH I55
J 0
(-2177 2500);
DISPLAY 0.872340 (-2177 2500);
PAINT GREEN (-2177 2500);
DISPLAY INVISIBLE (-2177 2500);
FORCEPROP 1 LAST HDL_TAP TRUE
J 0
(-1850 2375);
DISPLAY 1.446809 (-1850 2375);
PAINT GREEN (-1850 2375);
DISPLAY INVISIBLE (-1850 2375);
FORCEPROP 1 LAST BODY_TYPE PLUMBING
J 0
(-2175 2550);
DISPLAY 1.446809 (-2175 2550);
PAINT GREEN (-2175 2550);
DISPLAY INVISIBLE (-2175 2550);
FORCEPROP 2 LAST CDS_LIB mstr_standard
J 0
(-2175 2500);
PAINT MONO (-2175 2500);
DISPLAY INVISIBLE (-2175 2500);
FORCEADD TAP..1
(-2175 2850);
FORCEPROP 3 LASTPIN (-2225 2850) SIG_NAME P3E_CPU0_PE1_PCH_TXP<8>
J 0
(-2215 2860);
DISPLAY 0.659574 (-2215 2860);
PAINT MONO (-2215 2860);
DISPLAY INVISIBLE (-2215 2860);
FORCEPROP 1 LASTPIN (-2225 2850) BN 8
J 0
(-2237 2858);
DISPLAY 0.617021 (-2237 2858);
PAINT PINK (-2237 2858);
FORCEPROP 1 LAST PATH I56
J 0
(-2177 2850);
DISPLAY 0.872340 (-2177 2850);
PAINT GREEN (-2177 2850);
DISPLAY INVISIBLE (-2177 2850);
FORCEPROP 1 LAST HDL_TAP TRUE
J 0
(-1850 2725);
DISPLAY 1.446809 (-1850 2725);
PAINT GREEN (-1850 2725);
DISPLAY INVISIBLE (-1850 2725);
FORCEPROP 1 LAST BODY_TYPE PLUMBING
J 0
(-2175 2900);
DISPLAY 1.446809 (-2175 2900);
PAINT GREEN (-2175 2900);
DISPLAY INVISIBLE (-2175 2900);
FORCEPROP 2 LAST CDS_LIB mstr_standard
J 2
(-2175 2850);
PAINT MONO (-2175 2850);
DISPLAY INVISIBLE (-2175 2850);
FORCEADD TAP..1
(-2175 2950);
FORCEPROP 3 LASTPIN (-2225 2950) SIG_NAME P3E_CPU0_PE1_PCH_TXP<10>
J 0
(-2215 2960);
DISPLAY 0.659574 (-2215 2960);
PAINT MONO (-2215 2960);
DISPLAY INVISIBLE (-2215 2960);
FORCEPROP 1 LASTPIN (-2225 2950) BN 10
J 0
(-2237 2958);
DISPLAY 0.617021 (-2237 2958);
PAINT PINK (-2237 2958);
FORCEPROP 1 LAST PATH I57
J 0
(-2177 2950);
DISPLAY 0.872340 (-2177 2950);
PAINT GREEN (-2177 2950);
DISPLAY INVISIBLE (-2177 2950);
FORCEPROP 1 LAST HDL_TAP TRUE
J 0
(-1850 2825);
DISPLAY 1.446809 (-1850 2825);
PAINT GREEN (-1850 2825);
DISPLAY INVISIBLE (-1850 2825);
FORCEPROP 1 LAST BODY_TYPE PLUMBING
J 0
(-2175 3000);
DISPLAY 1.446809 (-2175 3000);
PAINT GREEN (-2175 3000);
DISPLAY INVISIBLE (-2175 3000);
FORCEPROP 2 LAST CDS_LIB mstr_standard
J 2
(-2175 2950);
PAINT MONO (-2175 2950);
DISPLAY INVISIBLE (-2175 2950);
FORCEADD TAP..1
(-2175 2900);
FORCEPROP 3 LASTPIN (-2225 2900) SIG_NAME P3E_CPU0_PE1_PCH_TXP<9>
J 0
(-2215 2910);
DISPLAY 0.659574 (-2215 2910);
PAINT MONO (-2215 2910);
DISPLAY INVISIBLE (-2215 2910);
FORCEPROP 1 LASTPIN (-2225 2900) BN 9
J 0
(-2237 2908);
DISPLAY 0.617021 (-2237 2908);
PAINT PINK (-2237 2908);
FORCEPROP 1 LAST PATH I58
J 0
(-2177 2900);
DISPLAY 0.872340 (-2177 2900);
PAINT GREEN (-2177 2900);
DISPLAY INVISIBLE (-2177 2900);
FORCEPROP 1 LAST HDL_TAP TRUE
J 0
(-1850 2775);
DISPLAY 1.446809 (-1850 2775);
PAINT GREEN (-1850 2775);
DISPLAY INVISIBLE (-1850 2775);
FORCEPROP 1 LAST BODY_TYPE PLUMBING
J 0
(-2175 2950);
DISPLAY 1.446809 (-2175 2950);
PAINT GREEN (-2175 2950);
DISPLAY INVISIBLE (-2175 2950);
FORCEPROP 2 LAST CDS_LIB mstr_standard
J 2
(-2175 2900);
PAINT MONO (-2175 2900);
DISPLAY INVISIBLE (-2175 2900);
FORCEADD TAP..1
(-2625 3100);
FORCEPROP 3 LASTPIN (-2675 3100) SIG_NAME P3E_CPU0_PE1_PCH_TXN<12>
J 0
(-2665 3110);
DISPLAY 0.659574 (-2665 3110);
PAINT MONO (-2665 3110);
DISPLAY INVISIBLE (-2665 3110);
FORCEPROP 1 LASTPIN (-2675 3100) BN 12
J 0
(-2687 3108);
DISPLAY 0.617021 (-2687 3108);
PAINT PINK (-2687 3108);
FORCEPROP 1 LAST PATH I59
J 0
(-2627 3100);
DISPLAY 0.872340 (-2627 3100);
PAINT GREEN (-2627 3100);
DISPLAY INVISIBLE (-2627 3100);
FORCEPROP 1 LAST HDL_TAP TRUE
J 0
(-2300 2975);
DISPLAY 1.446809 (-2300 2975);
PAINT GREEN (-2300 2975);
DISPLAY INVISIBLE (-2300 2975);
FORCEPROP 1 LAST BODY_TYPE PLUMBING
J 0
(-2625 3150);
DISPLAY 1.446809 (-2625 3150);
PAINT GREEN (-2625 3150);
DISPLAY INVISIBLE (-2625 3150);
FORCEPROP 2 LAST CDS_LIB mstr_standard
J 2
(-2625 3100);
PAINT MONO (-2625 3100);
DISPLAY INVISIBLE (-2625 3100);
FORCEADD TAP..1
R 2
(-5825 2000);
FORCEPROP 3 LASTPIN (-5775 2000) SIG_NAME P3E_CPU0_PE1_SS_RXP<3>
J 0
(-5765 2010);
DISPLAY 0.659574 (-5765 2010);
PAINT MONO (-5765 2010);
DISPLAY INVISIBLE (-5765 2010);
FORCEPROP 1 LASTPIN (-5775 2000) BN 3
J 2
(-5763 2008);
DISPLAY 0.617021 (-5763 2008);
PAINT PINK (-5763 2008);
FORCEPROP 1 LAST PATH I6
J 2
(-5823 2000);
DISPLAY 0.872340 (-5823 2000);
PAINT GREEN (-5823 2000);
DISPLAY INVISIBLE (-5823 2000);
FORCEPROP 1 LAST HDL_TAP TRUE
J 2
(-6150 1875);
DISPLAY 1.446809 (-6150 1875);
PAINT GREEN (-6150 1875);
DISPLAY INVISIBLE (-6150 1875);
FORCEPROP 1 LAST BODY_TYPE PLUMBING
J 2
(-5825 2050);
DISPLAY 1.446809 (-5825 2050);
PAINT GREEN (-5825 2050);
DISPLAY INVISIBLE (-5825 2050);
FORCEPROP 2 LAST CDS_LIB mstr_standard
J 0
(-5825 2000);
PAINT MONO (-5825 2000);
DISPLAY INVISIBLE (-5825 2000);
FORCEADD TAP..1
(-2625 3150);
FORCEPROP 3 LASTPIN (-2675 3150) SIG_NAME P3E_CPU0_PE1_PCH_TXN<13>
J 0
(-2665 3160);
DISPLAY 0.659574 (-2665 3160);
PAINT MONO (-2665 3160);
DISPLAY INVISIBLE (-2665 3160);
FORCEPROP 1 LASTPIN (-2675 3150) BN 13
J 0
(-2687 3158);
DISPLAY 0.617021 (-2687 3158);
PAINT PINK (-2687 3158);
FORCEPROP 1 LAST PATH I60
J 0
(-2627 3150);
DISPLAY 0.872340 (-2627 3150);
PAINT GREEN (-2627 3150);
DISPLAY INVISIBLE (-2627 3150);
FORCEPROP 1 LAST HDL_TAP TRUE
J 0
(-2300 3025);
DISPLAY 1.446809 (-2300 3025);
PAINT GREEN (-2300 3025);
DISPLAY INVISIBLE (-2300 3025);
FORCEPROP 1 LAST BODY_TYPE PLUMBING
J 0
(-2625 3200);
DISPLAY 1.446809 (-2625 3200);
PAINT GREEN (-2625 3200);
DISPLAY INVISIBLE (-2625 3200);
FORCEPROP 2 LAST CDS_LIB mstr_standard
J 2
(-2625 3150);
PAINT MONO (-2625 3150);
DISPLAY INVISIBLE (-2625 3150);
FORCEADD TAP..1
(-2625 3250);
FORCEPROP 3 LASTPIN (-2675 3250) SIG_NAME P3E_CPU0_PE1_PCH_TXN<15>
J 0
(-2665 3260);
DISPLAY 0.659574 (-2665 3260);
PAINT MONO (-2665 3260);
DISPLAY INVISIBLE (-2665 3260);
FORCEPROP 1 LASTPIN (-2675 3250) BN 15
J 0
(-2687 3258);
DISPLAY 0.617021 (-2687 3258);
PAINT PINK (-2687 3258);
FORCEPROP 1 LAST PATH I61
J 0
(-2627 3250);
DISPLAY 0.872340 (-2627 3250);
PAINT GREEN (-2627 3250);
DISPLAY INVISIBLE (-2627 3250);
FORCEPROP 1 LAST HDL_TAP TRUE
J 0
(-2300 3125);
DISPLAY 1.446809 (-2300 3125);
PAINT GREEN (-2300 3125);
DISPLAY INVISIBLE (-2300 3125);
FORCEPROP 1 LAST BODY_TYPE PLUMBING
J 0
(-2625 3300);
DISPLAY 1.446809 (-2625 3300);
PAINT GREEN (-2625 3300);
DISPLAY INVISIBLE (-2625 3300);
FORCEPROP 2 LAST CDS_LIB mstr_standard
J 2
(-2625 3250);
PAINT MONO (-2625 3250);
DISPLAY INVISIBLE (-2625 3250);
FORCEADD TAP..1
(-2625 3200);
FORCEPROP 3 LASTPIN (-2675 3200) SIG_NAME P3E_CPU0_PE1_PCH_TXN<14>
J 0
(-2665 3210);
DISPLAY 0.659574 (-2665 3210);
PAINT MONO (-2665 3210);
DISPLAY INVISIBLE (-2665 3210);
FORCEPROP 1 LASTPIN (-2675 3200) BN 14
J 0
(-2687 3208);
DISPLAY 0.617021 (-2687 3208);
PAINT PINK (-2687 3208);
FORCEPROP 1 LAST PATH I62
J 0
(-2627 3200);
DISPLAY 0.872340 (-2627 3200);
PAINT GREEN (-2627 3200);
DISPLAY INVISIBLE (-2627 3200);
FORCEPROP 1 LAST HDL_TAP TRUE
J 0
(-2300 3075);
DISPLAY 1.446809 (-2300 3075);
PAINT GREEN (-2300 3075);
DISPLAY INVISIBLE (-2300 3075);
FORCEPROP 1 LAST BODY_TYPE PLUMBING
J 0
(-2625 3250);
DISPLAY 1.446809 (-2625 3250);
PAINT GREEN (-2625 3250);
DISPLAY INVISIBLE (-2625 3250);
FORCEPROP 2 LAST CDS_LIB mstr_standard
J 2
(-2625 3200);
PAINT MONO (-2625 3200);
DISPLAY INVISIBLE (-2625 3200);
FORCEADD TAP..1
(-2175 3350);
FORCEPROP 3 LASTPIN (-2225 3350) SIG_NAME P3E_CPU0_PE1_PCH_TXP<12>
J 0
(-2215 3360);
DISPLAY 0.659574 (-2215 3360);
PAINT MONO (-2215 3360);
DISPLAY INVISIBLE (-2215 3360);
FORCEPROP 1 LASTPIN (-2225 3350) BN 12
J 0
(-2237 3358);
DISPLAY 0.617021 (-2237 3358);
PAINT PINK (-2237 3358);
FORCEPROP 1 LAST PATH I64
J 0
(-2177 3350);
DISPLAY 0.872340 (-2177 3350);
PAINT GREEN (-2177 3350);
DISPLAY INVISIBLE (-2177 3350);
FORCEPROP 1 LAST HDL_TAP TRUE
J 0
(-1850 3225);
DISPLAY 1.446809 (-1850 3225);
PAINT GREEN (-1850 3225);
DISPLAY INVISIBLE (-1850 3225);
FORCEPROP 1 LAST BODY_TYPE PLUMBING
J 0
(-2175 3400);
DISPLAY 1.446809 (-2175 3400);
PAINT GREEN (-2175 3400);
DISPLAY INVISIBLE (-2175 3400);
FORCEPROP 2 LAST CDS_LIB mstr_standard
J 2
(-2175 3350);
PAINT MONO (-2175 3350);
DISPLAY INVISIBLE (-2175 3350);
FORCEADD TAP..1
(-2175 3400);
FORCEPROP 3 LASTPIN (-2225 3400) SIG_NAME P3E_CPU0_PE1_PCH_TXP<13>
J 0
(-2215 3410);
DISPLAY 0.659574 (-2215 3410);
PAINT MONO (-2215 3410);
DISPLAY INVISIBLE (-2215 3410);
FORCEPROP 1 LASTPIN (-2225 3400) BN 13
J 0
(-2237 3408);
DISPLAY 0.617021 (-2237 3408);
PAINT PINK (-2237 3408);
FORCEPROP 1 LAST PATH I65
J 0
(-2177 3400);
DISPLAY 0.872340 (-2177 3400);
PAINT GREEN (-2177 3400);
DISPLAY INVISIBLE (-2177 3400);
FORCEPROP 1 LAST HDL_TAP TRUE
J 0
(-1850 3275);
DISPLAY 1.446809 (-1850 3275);
PAINT GREEN (-1850 3275);
DISPLAY INVISIBLE (-1850 3275);
FORCEPROP 1 LAST BODY_TYPE PLUMBING
J 0
(-2175 3450);
DISPLAY 1.446809 (-2175 3450);
PAINT GREEN (-2175 3450);
DISPLAY INVISIBLE (-2175 3450);
FORCEPROP 2 LAST CDS_LIB mstr_standard
J 2
(-2175 3400);
PAINT MONO (-2175 3400);
DISPLAY INVISIBLE (-2175 3400);
FORCEADD TAP..1
(-2175 3500);
FORCEPROP 3 LASTPIN (-2225 3500) SIG_NAME P3E_CPU0_PE1_PCH_TXP<15>
J 0
(-2215 3510);
DISPLAY 0.659574 (-2215 3510);
PAINT MONO (-2215 3510);
DISPLAY INVISIBLE (-2215 3510);
FORCEPROP 1 LASTPIN (-2225 3500) BN 15
J 0
(-2237 3508);
DISPLAY 0.617021 (-2237 3508);
PAINT PINK (-2237 3508);
FORCEPROP 1 LAST PATH I66
J 0
(-2177 3500);
DISPLAY 0.872340 (-2177 3500);
PAINT GREEN (-2177 3500);
DISPLAY INVISIBLE (-2177 3500);
FORCEPROP 1 LAST HDL_TAP TRUE
J 0
(-1850 3375);
DISPLAY 1.446809 (-1850 3375);
PAINT GREEN (-1850 3375);
DISPLAY INVISIBLE (-1850 3375);
FORCEPROP 1 LAST BODY_TYPE PLUMBING
J 0
(-2175 3550);
DISPLAY 1.446809 (-2175 3550);
PAINT GREEN (-2175 3550);
DISPLAY INVISIBLE (-2175 3550);
FORCEPROP 2 LAST CDS_LIB mstr_standard
J 2
(-2175 3500);
PAINT MONO (-2175 3500);
DISPLAY INVISIBLE (-2175 3500);
FORCEADD TAP..1
(-2175 3450);
FORCEPROP 3 LASTPIN (-2225 3450) SIG_NAME P3E_CPU0_PE1_PCH_TXP<14>
J 0
(-2215 3460);
DISPLAY 0.659574 (-2215 3460);
PAINT MONO (-2215 3460);
DISPLAY INVISIBLE (-2215 3460);
FORCEPROP 1 LASTPIN (-2225 3450) BN 14
J 0
(-2237 3458);
DISPLAY 0.617021 (-2237 3458);
PAINT PINK (-2237 3458);
FORCEPROP 1 LAST PATH I67
J 0
(-2177 3450);
DISPLAY 0.872340 (-2177 3450);
PAINT GREEN (-2177 3450);
DISPLAY INVISIBLE (-2177 3450);
FORCEPROP 1 LAST HDL_TAP TRUE
J 0
(-1850 3325);
DISPLAY 1.446809 (-1850 3325);
PAINT GREEN (-1850 3325);
DISPLAY INVISIBLE (-1850 3325);
FORCEPROP 1 LAST BODY_TYPE PLUMBING
J 0
(-2175 3500);
DISPLAY 1.446809 (-2175 3500);
PAINT GREEN (-2175 3500);
DISPLAY INVISIBLE (-2175 3500);
FORCEPROP 2 LAST CDS_LIB mstr_standard
J 2
(-2175 3450);
PAINT MONO (-2175 3450);
DISPLAY INVISIBLE (-2175 3450);
FORCEADD TAP..1
R 2
(-5825 2350);
FORCEPROP 3 LASTPIN (-5775 2350) SIG_NAME P3E_CPU0_PE1_SS_RXP<4>
J 0
(-5765 2360);
DISPLAY 0.659574 (-5765 2360);
PAINT MONO (-5765 2360);
DISPLAY INVISIBLE (-5765 2360);
FORCEPROP 1 LASTPIN (-5775 2350) BN 4
J 2
(-5763 2358);
DISPLAY 0.617021 (-5763 2358);
PAINT PINK (-5763 2358);
FORCEPROP 1 LAST PATH I7
J 2
(-5823 2350);
DISPLAY 0.872340 (-5823 2350);
PAINT GREEN (-5823 2350);
DISPLAY INVISIBLE (-5823 2350);
FORCEPROP 1 LAST HDL_TAP TRUE
J 2
(-6150 2225);
DISPLAY 1.446809 (-6150 2225);
PAINT GREEN (-6150 2225);
DISPLAY INVISIBLE (-6150 2225);
FORCEPROP 1 LAST BODY_TYPE PLUMBING
J 2
(-5825 2400);
DISPLAY 1.446809 (-5825 2400);
PAINT GREEN (-5825 2400);
DISPLAY INVISIBLE (-5825 2400);
FORCEPROP 2 LAST CDS_LIB mstr_standard
J 0
(-5825 2350);
PAINT MONO (-5825 2350);
DISPLAY INVISIBLE (-5825 2350);
FORCEADD OFFPAGE..1
(-6775 3650);
FORCEPROP 2 LAST $XR1 244 
J 0
(-7147 3650);
DISPLAY 0.638298 (-7147 3650);
PAINT MONO (-7147 3650);
FORCEPROP 2 LAST $XR0 105 
J 0
(-7027 3650);
DISPLAY 0.638298 (-7027 3650);
PAINT MONO (-7027 3650);
FORCEPROP 2 LAST PATH I70
J 0
(-7025 3700);
DISPLAY 1.021277 (-7025 3700);
PAINT ORANGE (-7025 3700);
DISPLAY INVISIBLE (-7025 3700);
FORCEPROP 1 LAST COMMENT_BODY TRUE
J 0
(-6650 3550);
DISPLAY 1.170213 (-6650 3550);
PAINT GREEN (-6650 3550);
DISPLAY INVISIBLE (-6650 3550);
FORCEPROP 1 LAST OFFPAGE TRUE
J 0
(-6450 3525);
PAINT GREEN (-6450 3525);
DISPLAY INVISIBLE (-6450 3525);
FORCEPROP 2 LAST CDS_LIB mstr_standard
J 0
(-6775 3650);
PAINT MONO (-6775 3650);
DISPLAY INVISIBLE (-6775 3650);
FORCEADD OFFPAGE..1
(-6775 3525);
FORCEPROP 2 LAST $XR1 244 
J 0
(-7147 3525);
DISPLAY 0.638298 (-7147 3525);
PAINT MONO (-7147 3525);
FORCEPROP 2 LAST $XR0 105 
J 0
(-7027 3525);
DISPLAY 0.638298 (-7027 3525);
PAINT MONO (-7027 3525);
FORCEPROP 2 LAST PATH I71
J 0
(-7025 3575);
DISPLAY 1.021277 (-7025 3575);
PAINT ORANGE (-7025 3575);
DISPLAY INVISIBLE (-7025 3575);
FORCEPROP 1 LAST COMMENT_BODY TRUE
J 0
(-6650 3425);
DISPLAY 1.170213 (-6650 3425);
PAINT GREEN (-6650 3425);
DISPLAY INVISIBLE (-6650 3425);
FORCEPROP 1 LAST OFFPAGE TRUE
J 0
(-6450 3400);
PAINT GREEN (-6450 3400);
DISPLAY INVISIBLE (-6450 3400);
FORCEPROP 2 LAST CDS_LIB mstr_standard
J 0
(-6775 3525);
PAINT MONO (-6775 3525);
DISPLAY INVISIBLE (-6775 3525);
FORCEADD OFFPAGE..2
(-1150 3575);
FORCEPROP 2 LAST $XR1 244 
J 0
(-841 3575);
DISPLAY 0.638298 (-841 3575);
PAINT MONO (-841 3575);
FORCEPROP 2 LAST $XR0 105 
J 0
(-961 3575);
DISPLAY 0.638298 (-961 3575);
PAINT MONO (-961 3575);
FORCEPROP 2 LAST PATH I74
J 0
(-975 3650);
DISPLAY 1.021277 (-975 3650);
PAINT ORANGE (-975 3650);
DISPLAY INVISIBLE (-975 3650);
FORCEPROP 1 LAST COMMENT_BODY TRUE
J 0
(-1195 3480);
DISPLAY 1.170213 (-1195 3480);
PAINT GREEN (-1195 3480);
DISPLAY INVISIBLE (-1195 3480);
FORCEPROP 1 LAST OFFPAGE TRUE
J 0
(-825 3450);
PAINT GREEN (-825 3450);
DISPLAY INVISIBLE (-825 3450);
FORCEPROP 2 LAST CDS_LIB mstr_standard
J 0
(-1150 3575);
PAINT ORANGE (-1150 3575);
DISPLAY INVISIBLE (-1150 3575);
FORCEADD OFFPAGE..2
(-1150 3725);
FORCEPROP 2 LAST $XR1 244 
J 0
(-841 3725);
DISPLAY 0.638298 (-841 3725);
PAINT MONO (-841 3725);
FORCEPROP 2 LAST $XR0 105 
J 0
(-961 3725);
DISPLAY 0.638298 (-961 3725);
PAINT MONO (-961 3725);
FORCEPROP 2 LAST PATH I75
J 0
(-975 3800);
DISPLAY 1.021277 (-975 3800);
PAINT ORANGE (-975 3800);
DISPLAY INVISIBLE (-975 3800);
FORCEPROP 1 LAST COMMENT_BODY TRUE
J 0
(-1195 3630);
DISPLAY 1.170213 (-1195 3630);
PAINT GREEN (-1195 3630);
DISPLAY INVISIBLE (-1195 3630);
FORCEPROP 1 LAST OFFPAGE TRUE
J 0
(-825 3600);
PAINT GREEN (-825 3600);
DISPLAY INVISIBLE (-825 3600);
FORCEPROP 2 LAST CDS_LIB mstr_standard
J 0
(-1150 3725);
PAINT ORANGE (-1150 3725);
DISPLAY INVISIBLE (-1150 3725);
FORCEADD TAP..1
(-2175 3000);
FORCEPROP 3 LASTPIN (-2225 3000) SIG_NAME P3E_CPU0_PE1_PCH_TXP<11>
J 0
(-2215 3010);
DISPLAY 0.659574 (-2215 3010);
PAINT MONO (-2215 3010);
DISPLAY INVISIBLE (-2215 3010);
FORCEPROP 1 LASTPIN (-2225 3000) BN 11
J 0
(-2237 3008);
DISPLAY 0.617021 (-2237 3008);
PAINT GREEN (-2237 3008);
FORCEPROP 1 LAST PATH I78
J 0
(-2177 3000);
DISPLAY 0.872340 (-2177 3000);
PAINT GREEN (-2177 3000);
DISPLAY INVISIBLE (-2177 3000);
FORCEPROP 1 LAST HDL_TAP TRUE
J 0
(-1850 2875);
DISPLAY 1.446809 (-1850 2875);
PAINT GREEN (-1850 2875);
DISPLAY INVISIBLE (-1850 2875);
FORCEPROP 1 LAST BODY_TYPE PLUMBING
J 0
(-2175 3050);
DISPLAY 1.446809 (-2175 3050);
PAINT GREEN (-2175 3050);
DISPLAY INVISIBLE (-2175 3050);
FORCEPROP 2 LAST CDS_LIB mstr_standard
J 0
(-2175 3000);
PAINT ORANGE (-2175 3000);
DISPLAY INVISIBLE (-2175 3000);
FORCEADD TAP..1
(-2625 2750);
FORCEPROP 3 LASTPIN (-2675 2750) SIG_NAME P3E_CPU0_PE1_PCH_TXN<11>
J 0
(-2665 2760);
DISPLAY 0.659574 (-2665 2760);
PAINT MONO (-2665 2760);
DISPLAY INVISIBLE (-2665 2760);
FORCEPROP 1 LASTPIN (-2675 2750) BN 11
J 0
(-2687 2758);
DISPLAY 0.617021 (-2687 2758);
PAINT PINK (-2687 2758);
FORCEPROP 1 LAST PATH I79
J 0
(-2627 2750);
DISPLAY 0.872340 (-2627 2750);
PAINT GREEN (-2627 2750);
DISPLAY INVISIBLE (-2627 2750);
FORCEPROP 1 LAST HDL_TAP TRUE
J 0
(-2300 2625);
DISPLAY 1.446809 (-2300 2625);
PAINT GREEN (-2300 2625);
DISPLAY INVISIBLE (-2300 2625);
FORCEPROP 1 LAST BODY_TYPE PLUMBING
J 0
(-2625 2800);
DISPLAY 1.446809 (-2625 2800);
PAINT GREEN (-2625 2800);
DISPLAY INVISIBLE (-2625 2800);
FORCEPROP 2 LAST CDS_LIB mstr_standard
J 2
(-2625 2750);
PAINT MONO (-2625 2750);
DISPLAY INVISIBLE (-2625 2750);
FORCEADD TAP..1
R 2
(-5825 2400);
FORCEPROP 3 LASTPIN (-5775 2400) SIG_NAME P3E_CPU0_PE1_SS_RXP<5>
J 0
(-5765 2410);
DISPLAY 0.659574 (-5765 2410);
PAINT MONO (-5765 2410);
DISPLAY INVISIBLE (-5765 2410);
FORCEPROP 1 LASTPIN (-5775 2400) BN 5
J 2
(-5763 2408);
DISPLAY 0.617021 (-5763 2408);
PAINT PINK (-5763 2408);
FORCEPROP 1 LAST PATH I8
J 2
(-5823 2400);
DISPLAY 0.872340 (-5823 2400);
PAINT GREEN (-5823 2400);
DISPLAY INVISIBLE (-5823 2400);
FORCEPROP 1 LAST HDL_TAP TRUE
J 2
(-6150 2275);
DISPLAY 1.446809 (-6150 2275);
PAINT GREEN (-6150 2275);
DISPLAY INVISIBLE (-6150 2275);
FORCEPROP 1 LAST BODY_TYPE PLUMBING
J 2
(-5825 2450);
DISPLAY 1.446809 (-5825 2450);
PAINT GREEN (-5825 2450);
DISPLAY INVISIBLE (-5825 2450);
FORCEPROP 2 LAST CDS_LIB mstr_standard
J 0
(-5825 2400);
PAINT MONO (-5825 2400);
DISPLAY INVISIBLE (-5825 2400);
FORCEADD OFFPAGE..2
(-1075 1550);
FORCEPROP 2 LAST $XR0 107 
J 0
(-886 1550);
DISPLAY 0.638298 (-886 1550);
PAINT MONO (-886 1550);
FORCEPROP 2 LAST PATH I80
J 0
(-900 1625);
DISPLAY 1.021277 (-900 1625);
PAINT ORANGE (-900 1625);
DISPLAY INVISIBLE (-900 1625);
FORCEPROP 1 LAST COMMENT_BODY TRUE
J 0
(-1120 1455);
DISPLAY 1.170213 (-1120 1455);
PAINT GREEN (-1120 1455);
DISPLAY INVISIBLE (-1120 1455);
FORCEPROP 1 LAST OFFPAGE TRUE
J 0
(-750 1425);
PAINT GREEN (-750 1425);
DISPLAY INVISIBLE (-750 1425);
FORCEPROP 2 LAST CDS_LIB mstr_standard
J 0
(-1075 1550);
PAINT ORANGE (-1075 1550);
DISPLAY INVISIBLE (-1075 1550);
FORCEADD OFFPAGE..2
(-1100 1775);
FORCEPROP 2 LAST $XR0 107 
J 0
(-911 1775);
DISPLAY 0.638298 (-911 1775);
PAINT MONO (-911 1775);
FORCEPROP 2 LAST PATH I81
J 0
(-925 1850);
DISPLAY 1.021277 (-925 1850);
PAINT ORANGE (-925 1850);
DISPLAY INVISIBLE (-925 1850);
FORCEPROP 1 LAST COMMENT_BODY TRUE
J 0
(-1145 1680);
DISPLAY 1.170213 (-1145 1680);
PAINT GREEN (-1145 1680);
DISPLAY INVISIBLE (-1145 1680);
FORCEPROP 1 LAST OFFPAGE TRUE
J 0
(-775 1650);
PAINT GREEN (-775 1650);
DISPLAY INVISIBLE (-775 1650);
FORCEPROP 2 LAST CDS_LIB mstr_standard
J 0
(-1100 1775);
PAINT ORANGE (-1100 1775);
DISPLAY INVISIBLE (-1100 1775);
FORCEADD OFFPAGE..1
(-6975 1800);
FORCEPROP 2 LAST $XR0 107 
J 0
(-7227 1800);
DISPLAY 0.638298 (-7227 1800);
PAINT MONO (-7227 1800);
FORCEPROP 2 LAST PATH I82
J 0
(-6925 1875);
DISPLAY 1.021277 (-6925 1875);
PAINT ORANGE (-6925 1875);
DISPLAY INVISIBLE (-6925 1875);
FORCEPROP 1 LAST COMMENT_BODY TRUE
J 0
(-6850 1700);
DISPLAY 1.170213 (-6850 1700);
PAINT GREEN (-6850 1700);
DISPLAY INVISIBLE (-6850 1700);
FORCEPROP 1 LAST OFFPAGE TRUE
J 0
(-6650 1675);
PAINT GREEN (-6650 1675);
DISPLAY INVISIBLE (-6650 1675);
FORCEPROP 2 LAST CDS_LIB mstr_standard
J 0
(-6975 1800);
PAINT ORANGE (-6975 1800);
DISPLAY INVISIBLE (-6975 1800);
FORCEADD OFFPAGE..1
(-6975 1525);
FORCEPROP 2 LAST $XR0 107 
J 0
(-7227 1525);
DISPLAY 0.638298 (-7227 1525);
PAINT MONO (-7227 1525);
FORCEPROP 2 LAST PATH I83
J 0
(-6925 1600);
DISPLAY 1.021277 (-6925 1600);
PAINT ORANGE (-6925 1600);
DISPLAY INVISIBLE (-6925 1600);
FORCEPROP 1 LAST COMMENT_BODY TRUE
J 0
(-6850 1425);
DISPLAY 1.170213 (-6850 1425);
PAINT GREEN (-6850 1425);
DISPLAY INVISIBLE (-6850 1425);
FORCEPROP 1 LAST OFFPAGE TRUE
J 0
(-6650 1400);
PAINT GREEN (-6650 1400);
DISPLAY INVISIBLE (-6650 1400);
FORCEPROP 2 LAST CDS_LIB mstr_standard
J 0
(-6975 1525);
PAINT ORANGE (-6975 1525);
DISPLAY INVISIBLE (-6975 1525);
FORCEADD SKX_EXT_B..10
(-4100 2550);
FORCEPROP 2 LASTPIN (-4850 1900) $PN CY7
J 2
(-4860 1910);
DISPLAY 0.617021 (-4860 1910);
PAINT ORANGE (-4860 1910);
FORCEPROP 2 LASTPIN (-3350 1900) $PN DB1
J 0
(-3340 1910);
DISPLAY 0.617021 (-3340 1910);
PAINT ORANGE (-3340 1910);
FORCEPROP 2 LASTPIN (-4850 3150) $PN DW14
J 2
(-4860 3160);
DISPLAY 0.617021 (-4860 3160);
PAINT ORANGE (-4860 3160);
FORCEPROP 2 LASTPIN (-4850 1600) $PN CW8
J 2
(-4860 1610);
DISPLAY 0.617021 (-4860 1610);
PAINT ORANGE (-4860 1610);
FORCEPROP 2 LASTPIN (-4850 1650) $PN DA8
J 2
(-4860 1660);
DISPLAY 0.617021 (-4860 1660);
PAINT ORANGE (-4860 1660);
FORCEPROP 2 LASTPIN (-4850 1700) $PN DC8
J 2
(-4860 1710);
DISPLAY 0.617021 (-4860 1710);
PAINT ORANGE (-4860 1710);
FORCEPROP 2 LASTPIN (-4850 1750) $PN DC10
J 2
(-4860 1760);
DISPLAY 0.617021 (-4860 1760);
PAINT ORANGE (-4860 1760);
FORCEPROP 2 LASTPIN (-4850 2100) $PN DE10
J 2
(-4860 2110);
DISPLAY 0.617021 (-4860 2110);
PAINT ORANGE (-4860 2110);
FORCEPROP 2 LASTPIN (-4850 2150) $PN DH9
J 2
(-4860 2160);
DISPLAY 0.617021 (-4860 2160);
PAINT ORANGE (-4860 2160);
FORCEPROP 2 LASTPIN (-4850 2200) $PN DK9
J 2
(-4860 2210);
DISPLAY 0.617021 (-4860 2210);
PAINT ORANGE (-4860 2210);
FORCEPROP 2 LASTPIN (-4850 2250) $PN DM9
J 2
(-4860 2260);
DISPLAY 0.617021 (-4860 2260);
PAINT ORANGE (-4860 2260);
FORCEPROP 2 LASTPIN (-4850 2600) $PN DM11
J 2
(-4860 2610);
DISPLAY 0.617021 (-4860 2610);
PAINT ORANGE (-4860 2610);
FORCEPROP 2 LASTPIN (-4850 2650) $PN DP11
J 2
(-4860 2660);
DISPLAY 0.617021 (-4860 2660);
PAINT ORANGE (-4860 2660);
FORCEPROP 2 LASTPIN (-4850 2700) $PN DT11
J 2
(-4860 2710);
DISPLAY 0.617021 (-4860 2710);
PAINT ORANGE (-4860 2710);
FORCEPROP 2 LASTPIN (-4850 2750) $PN DT13
J 2
(-4860 2760);
DISPLAY 0.617021 (-4860 2760);
PAINT ORANGE (-4860 2760);
FORCEPROP 2 LASTPIN (-4850 3100) $PN DV13
J 2
(-4860 3110);
DISPLAY 0.617021 (-4860 3110);
PAINT ORANGE (-4860 3110);
FORCEPROP 2 LASTPIN (-4850 3200) $PN DY15
J 2
(-4860 3210);
DISPLAY 0.617021 (-4860 3210);
PAINT ORANGE (-4860 3210);
FORCEPROP 2 LASTPIN (-4850 3250) $PN DU16
J 2
(-4860 3260);
DISPLAY 0.617021 (-4860 3260);
PAINT ORANGE (-4860 3260);
FORCEPROP 2 LASTPIN (-4850 1850) $PN CU8
J 2
(-4860 1860);
DISPLAY 0.617021 (-4860 1860);
PAINT ORANGE (-4860 1860);
FORCEPROP 2 LASTPIN (-4850 1950) $PN DB9
J 2
(-4860 1960);
DISPLAY 0.617021 (-4860 1960);
PAINT ORANGE (-4860 1960);
FORCEPROP 2 LASTPIN (-4850 2000) $PN DA10
J 2
(-4860 2010);
DISPLAY 0.617021 (-4860 2010);
PAINT ORANGE (-4860 2010);
FORCEPROP 2 LASTPIN (-4850 2350) $PN DD9
J 2
(-4860 2360);
DISPLAY 0.617021 (-4860 2360);
PAINT ORANGE (-4860 2360);
FORCEPROP 2 LASTPIN (-4850 2400) $PN DF9
J 2
(-4860 2410);
DISPLAY 0.617021 (-4860 2410);
PAINT ORANGE (-4860 2410);
FORCEPROP 2 LASTPIN (-4850 2450) $PN DJ8
J 2
(-4860 2460);
DISPLAY 0.617021 (-4860 2460);
PAINT ORANGE (-4860 2460);
FORCEPROP 2 LASTPIN (-4850 2850) $PN DK11
J 2
(-4860 2860);
DISPLAY 0.617021 (-4860 2860);
PAINT ORANGE (-4860 2860);
FORCEPROP 2 LASTPIN (-4850 2900) $PN DN10
J 2
(-4860 2910);
DISPLAY 0.617021 (-4860 2910);
PAINT ORANGE (-4860 2910);
FORCEPROP 2 LASTPIN (-4850 2950) $PN DR12
J 2
(-4860 2960);
DISPLAY 0.617021 (-4860 2960);
PAINT ORANGE (-4860 2960);
FORCEPROP 2 LASTPIN (-4850 3000) $PN DP13
J 2
(-4860 3010);
DISPLAY 0.617021 (-4860 3010);
PAINT ORANGE (-4860 3010);
FORCEPROP 2 LASTPIN (-4850 3350) $PN DU12
J 2
(-4860 3360);
DISPLAY 0.617021 (-4860 3360);
PAINT ORANGE (-4860 3360);
FORCEPROP 2 LASTPIN (-4850 3400) $PN DY13
J 2
(-4860 3410);
DISPLAY 0.617021 (-4860 3410);
PAINT ORANGE (-4860 3410);
FORCEPROP 2 LASTPIN (-4850 3450) $PN DV15
J 2
(-4860 3460);
DISPLAY 0.617021 (-4860 3460);
PAINT ORANGE (-4860 3460);
FORCEPROP 2 LASTPIN (-4850 3500) $PN DT15
J 2
(-4860 3510);
DISPLAY 0.617021 (-4860 3510);
PAINT ORANGE (-4860 3510);
FORCEPROP 2 LASTPIN (-3350 1600) $PN DA2
J 0
(-3340 1610);
DISPLAY 0.617021 (-3340 1610);
PAINT ORANGE (-3340 1610);
FORCEPROP 2 LASTPIN (-3350 1650) $PN DC2
J 0
(-3340 1660);
DISPLAY 0.617021 (-3340 1660);
PAINT ORANGE (-3340 1660);
FORCEPROP 2 LASTPIN (-3350 1700) $PN DE2
J 0
(-3340 1710);
DISPLAY 0.617021 (-3340 1710);
PAINT ORANGE (-3340 1710);
FORCEPROP 2 LASTPIN (-3350 1750) $PN DE4
J 0
(-3340 1760);
DISPLAY 0.617021 (-3340 1760);
PAINT ORANGE (-3340 1760);
FORCEPROP 2 LASTPIN (-3350 2100) $PN DG4
J 0
(-3340 2110);
DISPLAY 0.617021 (-3340 2110);
PAINT ORANGE (-3340 2110);
FORCEPROP 2 LASTPIN (-3350 2150) $PN DK3
J 0
(-3340 2160);
DISPLAY 0.617021 (-3340 2160);
PAINT ORANGE (-3340 2160);
FORCEPROP 2 LASTPIN (-3350 2200) $PN DM3
J 0
(-3340 2210);
DISPLAY 0.617021 (-3340 2210);
PAINT ORANGE (-3340 2210);
FORCEPROP 2 LASTPIN (-3350 2250) $PN DN4
J 0
(-3340 2260);
DISPLAY 0.617021 (-3340 2260);
PAINT ORANGE (-3340 2260);
FORCEPROP 2 LASTPIN (-3350 2600) $PN DT5
J 0
(-3340 2610);
DISPLAY 0.617021 (-3340 2610);
PAINT ORANGE (-3340 2610);
FORCEPROP 2 LASTPIN (-3350 2650) $PN DV3
J 0
(-3340 2660);
DISPLAY 0.617021 (-3340 2660);
PAINT ORANGE (-3340 2660);
FORCEPROP 2 LASTPIN (-3350 2750) $PN DU6
J 0
(-3340 2760);
DISPLAY 0.617021 (-3340 2760);
PAINT ORANGE (-3340 2760);
FORCEPROP 2 LASTPIN (-3350 3100) $PN DV7
J 0
(-3340 3110);
DISPLAY 0.617021 (-3340 3110);
PAINT ORANGE (-3340 3110);
FORCEPROP 2 LASTPIN (-3350 3150) $PN DY7
J 0
(-3340 3160);
DISPLAY 0.617021 (-3340 3160);
PAINT ORANGE (-3340 3160);
FORCEPROP 2 LASTPIN (-3350 3200) $PN EA8
J 0
(-3340 3210);
DISPLAY 0.617021 (-3340 3210);
PAINT ORANGE (-3340 3210);
FORCEPROP 2 LASTPIN (-3350 3250) $PN ED9
J 0
(-3340 3260);
DISPLAY 0.617021 (-3340 3260);
PAINT ORANGE (-3340 3260);
FORCEPROP 2 LASTPIN (-3350 1850) $PN CW2
J 0
(-3340 1860);
DISPLAY 0.617021 (-3340 1860);
PAINT ORANGE (-3340 1860);
FORCEPROP 2 LASTPIN (-3350 1950) $PN DD3
J 0
(-3340 1960);
DISPLAY 0.617021 (-3340 1960);
PAINT ORANGE (-3340 1960);
FORCEPROP 2 LASTPIN (-3350 2000) $PN DC4
J 0
(-3340 2010);
DISPLAY 0.617021 (-3340 2010);
PAINT ORANGE (-3340 2010);
FORCEPROP 2 LASTPIN (-3350 2350) $PN DF3
J 0
(-3340 2360);
DISPLAY 0.617021 (-3340 2360);
PAINT ORANGE (-3340 2360);
FORCEPROP 2 LASTPIN (-3350 2400) $PN DH3
J 0
(-3340 2410);
DISPLAY 0.617021 (-3340 2410);
PAINT ORANGE (-3340 2410);
FORCEPROP 2 LASTPIN (-3350 2450) $PN DL2
J 0
(-3340 2460);
DISPLAY 0.617021 (-3340 2460);
PAINT ORANGE (-3340 2460);
FORCEPROP 2 LASTPIN (-3350 2500) $PN DP3
J 0
(-3340 2510);
DISPLAY 0.617021 (-3340 2510);
PAINT ORANGE (-3340 2510);
FORCEPROP 2 LASTPIN (-3350 2850) $PN DR4
J 0
(-3340 2860);
DISPLAY 0.617021 (-3340 2860);
PAINT ORANGE (-3340 2860);
FORCEPROP 2 LASTPIN (-3350 2900) $PN DU2
J 0
(-3340 2910);
DISPLAY 0.617021 (-3340 2910);
PAINT ORANGE (-3340 2910);
FORCEPROP 2 LASTPIN (-3350 2950) $PN DU4
J 0
(-3340 2960);
DISPLAY 0.617021 (-3340 2960);
PAINT ORANGE (-3340 2960);
FORCEPROP 2 LASTPIN (-3350 3000) $PN DV5
J 0
(-3340 3010);
DISPLAY 0.617021 (-3340 3010);
PAINT ORANGE (-3340 3010);
FORCEPROP 2 LASTPIN (-3350 3350) $PN DT7
J 0
(-3340 3360);
DISPLAY 0.617021 (-3340 3360);
PAINT ORANGE (-3340 3360);
FORCEPROP 2 LASTPIN (-3350 3400) $PN DW6
J 0
(-3340 3410);
DISPLAY 0.617021 (-3340 3410);
PAINT ORANGE (-3340 3410);
FORCEPROP 2 LASTPIN (-3350 3450) $PN EB7
J 0
(-3340 3460);
DISPLAY 0.617021 (-3340 3460);
PAINT ORANGE (-3340 3460);
FORCEPROP 2 LASTPIN (-3350 3500) $PN EC8
J 0
(-3340 3510);
DISPLAY 0.617021 (-3340 3510);
PAINT ORANGE (-3340 3510);
FORCEPROP 1 LAST MATERIAL IC
J 0
(-4800 3700);
DISPLAY 0.617021 (-4800 3700);
PAINT SKYBLUE (-4800 3700);
FORCEPROP 1 LAST PART_NUMBER TBD
J 0
(-4800 1400);
DISPLAY 0.617021 (-4800 1400);
PAINT BLUE (-4800 1400);
FORCEPROP 1 LAST LOCATION U5D1
J 0
(-4800 3750);
DISPLAY 0.617021 (-4800 3750);
PAINT AQUA (-4800 3750);
FORCEPROP 2 LASTPIN (-4850 2500) $PN DL10
J 2
(-4860 2510);
DISPLAY 0.617021 (-4860 2510);
PAINT ORANGE (-4860 2510);
FORCEPROP 2 LASTPIN (-3350 2700) $PN DW4
J 0
(-3340 2710);
DISPLAY 0.617021 (-3340 2710);
PAINT ORANGE (-3340 2710);
FORCEPROP 0 LAST ROOM CPU0
J 0
(-4800 3850);
DISPLAY 1.021277 (-4800 3850);
PAINT ORANGE (-4800 3850);
DISPLAY INVISIBLE (-4800 3850);
FORCEPROP 1 LAST PATH I84
J 0
(-4100 3700);
PAINT GREEN (-4100 3700);
DISPLAY INVISIBLE (-4100 3700);
FORCEPROP 2 LAST CDS_LOCATION U5D1
J 0
(-4800 3750);
DISPLAY 0.617021 (-4800 3750);
PAINT AQUA (-4800 3750);
DISPLAY INVISIBLE (-4800 3750);
FORCEPROP 2 LAST SEC 10
J 0
(-4800 3800);
DISPLAY 0.680851 (-4800 3800);
PAINT MONO (-4800 3800);
DISPLAY INVISIBLE (-4800 3800);
FORCEPROP 2 LAST SEC_TYPE BGA1
J 0
(-4800 3800);
DISPLAY 1.021277 (-4800 3800);
PAINT ORANGE (-4800 3800);
DISPLAY INVISIBLE (-4800 3800);
FORCEPROP 2 LAST CDS_LIB chpset_lib
J 0
(-4100 2550);
PAINT ORANGE (-4100 2550);
DISPLAY INVISIBLE (-4100 2550);
FORCEPROP 1 LAST PACK_TYPE BGA1
J 0
(-4800 3800);
PAINT SKYBLUE (-4800 3800);
DISPLAY INVISIBLE (-4800 3800);
FORCEADD TAP..1
R 2
(-5825 2450);
FORCEPROP 3 LASTPIN (-5775 2450) SIG_NAME P3E_CPU0_PE1_SS_RXP<6>
J 0
(-5765 2460);
DISPLAY 0.659574 (-5765 2460);
PAINT MONO (-5765 2460);
DISPLAY INVISIBLE (-5765 2460);
FORCEPROP 1 LASTPIN (-5775 2450) BN 6
J 2
(-5763 2458);
DISPLAY 0.617021 (-5763 2458);
PAINT PINK (-5763 2458);
FORCEPROP 1 LAST PATH I9
J 2
(-5823 2450);
DISPLAY 0.872340 (-5823 2450);
PAINT GREEN (-5823 2450);
DISPLAY INVISIBLE (-5823 2450);
FORCEPROP 1 LAST HDL_TAP TRUE
J 2
(-6150 2325);
DISPLAY 1.446809 (-6150 2325);
PAINT GREEN (-6150 2325);
DISPLAY INVISIBLE (-6150 2325);
FORCEPROP 1 LAST BODY_TYPE PLUMBING
J 2
(-5825 2500);
DISPLAY 1.446809 (-5825 2500);
PAINT GREEN (-5825 2500);
DISPLAY INVISIBLE (-5825 2500);
FORCEPROP 2 LAST CDS_LIB mstr_standard
J 0
(-5825 2450);
PAINT MONO (-5825 2450);
DISPLAY INVISIBLE (-5825 2450);
FORCEADD INTEL_CORP_BPAGE..1
(0 0);
FORCEPROP 1 LAST CDS_CON_LAST_MODIFIED Fri Jun 16 17:48:12 2017
J 0
(-1425 325);
DISPLAY 1.340426 (-1425 325);
PAINT GREEN (-1425 325);
DISPLAY INVISIBLE (-1425 325);
FORCEPROP 1 LAST CUSTOM_TXT_CDS <CURRENT_DESIGN_SHEET> OF <TOTAL_DESIGN_SHEETS>
J 0
(-500 25);
PAINT ORANGE (-500 25);
FORCEPROP 1 LAST CUSTOM_TXT_CDS <CON_LAST_MODIFIED>
J 0
(-4000 100);
PAINT ORANGE (-4000 100);
FORCEPROP 2 LAST CUSTOM_TXT_CDS <XR_PAGE_TITLE>
J 0
(-7890 5250);
DISPLAY 0.638298 (-7890 5250);
PAINT PINK (-7890 5250);
DISPLAY INVISIBLE (-7890 5250);
FORCEPROP 1 LAST SCH_TITLE SKYLAKE - SKT0 - 10 OF 21
J 0
(-7950 50);
DISPLAY 1.212766 (-7950 50);
PAINT GREEN (-7950 50);
FORCEPROP 1 LAST COMMENT_BODY TRUE
J 0
(12 12);
DISPLAY 0.638298 (12 12);
PAINT GREEN (12 12);
DISPLAY INVISIBLE (12 12);
FORCEPROP 2 LAST CDS_LIB mstr_symbols
J 0
(0 0);
PAINT ORANGE (0 0);
DISPLAY INVISIBLE (0 0);
FORCEPROP 2 LAST PAGE_BORDER TRUE
J 0
(-7890 5250);
DISPLAY 0.851064 (-7890 5250);
PAINT PINK (-7890 5250);
DISPLAY INVISIBLE (-7890 5250);
FORCEPROP 2 LAST CDS_XR_PAGE_TITLE CR-30 : @BASEBOARD_FAB2_LIB.BASEBOARD_FAB2(SCH_1):PAGE30
J 0
(-7890 5250);
DISPLAY 0.638298 (-7890 5250);
PAINT PINK (-7890 5250);
DISPLAY INVISIBLE (-7890 5250);
FORCEADD DESIGN_NOTE..1
(-4600 1300);
FORCEPROP 0 LAST L1 CPU SYMBOLS 1-30 ARE PRELIMINARY AND SUBJECT TO CHANGE
J 0
(-4800 1175);
DISPLAY 1.021277 (-4800 1175);
PAINT ORANGE (-4800 1175);
FORCEPROP 1 LAST COMMENT_BODY TRUE
J 0
(-4575 1400);
DISPLAY 0.978723 (-4575 1400);
PAINT ORANGE (-4575 1400);
DISPLAY INVISIBLE (-4575 1400);
FORCEPROP 2 LAST CDS_LIB mstr_symbols
J 0
(-4600 1300);
PAINT ORANGE (-4600 1300);
DISPLAY INVISIBLE (-4600 1300);
FORCEADD PRELIM..10
(-4090 2540);
PAINT GRAY (-4090 2540);
FORCEPROP 1 LAST COMMENT_BODY TRUE
J 0
(-4090 2540);
PAINT ORANGE (-4090 2540);
DISPLAY INVISIBLE (-4090 2540);
FORCEPROP 2 LAST CDS_LIB mstr_misc
J 0
(-4090 2540);
PAINT ORANGE (-4090 2540);
DISPLAY INVISIBLE (-4090 2540);
WIRE 17 -1 (-5600 2225)(-5600 2275);
WIRE 17 -1 (-5600 1525)(-6925 1525);
FORCEPROP 0 LAST SIG_NAME P3E_CPU0_PE1_SS_RXN<7:0>
J 0
(-6860 1535);
DISPLAY 0.617021 (-6860 1535);
PAINT ORANGE (-6860 1535);
WIRE 17 -1 (-5600 1625)(-5600 1525);
WIRE 17 -1 (-5600 2225)(-5600 2175);
WIRE 17 -1 (-5600 2175)(-5600 2125);
WIRE 17 -1 (-5600 1675)(-5600 1625);
WIRE 17 -1 (-5600 1725)(-5600 1675);
WIRE 17 -1 (-5600 2125)(-5600 1775);
WIRE 17 -1 (-5600 1775)(-5600 1725);
WIRE 17 -1 (-5875 2475)(-5875 2525);
WIRE 17 -1 (-5875 2425)(-5875 2475);
WIRE 17 -1 (-5875 2375)(-5875 2425);
WIRE 17 -1 (-5875 2025)(-5875 2375);
WIRE 17 -1 (-5875 1800)(-6925 1800);
FORCEPROP 2 LAST SIG_NAME P3E_CPU0_PE1_SS_RXP<7:0>
J 0
(-6885 1810);
DISPLAY 0.617021 (-6885 1810);
PAINT ORANGE (-6885 1810);
WIRE 17 -1 (-5875 1975)(-5875 2025);
WIRE 17 -1 (-5875 1925)(-5875 1975);
WIRE 17 -1 (-5875 1875)(-5875 1800);
WIRE 17 -1 (-5875 1875)(-5875 1925);
WIRE 17 -1 (-2575 1550)(-1125 1550);
FORCEPROP 2 LAST SIG_NAME P3E_CPU0_PE1_SS_TXN<7:0>
J 0
(-2060 1560);
DISPLAY 0.617021 (-2060 1560);
PAINT ORANGE (-2060 1560);
WIRE 17 -1 (-2575 1625)(-2575 1550);
WIRE 17 -1 (-2575 1675)(-2575 1625);
WIRE 17 -1 (-2575 1675)(-2575 1725);
WIRE 17 -1 (-2575 2225)(-2575 2275);
WIRE 17 -1 (-2575 1725)(-2575 1775);
WIRE 17 -1 (-2575 1775)(-2575 2125);
WIRE 17 -1 (-2575 2225)(-2575 2175);
WIRE 17 -1 (-2575 2175)(-2575 2125);
WIRE 17 -1 (-2125 2525)(-2125 2475);
WIRE 17 -1 (-2125 2475)(-2125 2425);
WIRE 17 -1 (-2125 2425)(-2125 2375);
WIRE 17 -1 (-2125 2025)(-2125 2375);
WIRE 17 -1 (-2125 1975)(-2125 2025);
WIRE 17 -1 (-2125 1775)(-1150 1775);
FORCEPROP 2 LAST SIG_NAME P3E_CPU0_PE1_SS_TXP<7:0>
J 0
(-2035 1785);
DISPLAY 0.617021 (-2035 1785);
PAINT ORANGE (-2035 1785);
WIRE 17 -1 (-2125 1875)(-2125 1775);
WIRE 17 -1 (-2125 1925)(-2125 1975);
WIRE 17 -1 (-2125 1925)(-2125 1875);
WIRE 17 -1 (-5600 2675)(-5600 2625);
WIRE 17 -1 (-5600 2725)(-5600 2675);
WIRE 17 -1 (-5600 2775)(-5600 2725);
WIRE 17 -1 (-5600 3650)(-6725 3650);
FORCEPROP 0 LAST SIG_NAME P3E_CPU0_PE1_PCH_RXN<15:8>
J 0
(-6710 3660);
DISPLAY 0.617021 (-6710 3660);
PAINT ORANGE (-6710 3660);
WIRE 17 -1 (-5600 3650)(-5600 3275);
WIRE 17 -1 (-5600 3125)(-5600 2775);
WIRE 17 -1 (-5600 3175)(-5600 3125);
WIRE 17 -1 (-5600 3225)(-5600 3275);
WIRE 17 -1 (-5600 3225)(-5600 3175);
WIRE 17 -1 (-6725 3525)(-5875 3525);
FORCEPROP 2 LAST SIG_NAME P3E_CPU0_PE1_PCH_RXP<15:8>
J 0
(-6685 3535);
DISPLAY 0.617021 (-6685 3535);
PAINT ORANGE (-6685 3535);
WIRE 17 -1 (-5875 3475)(-5875 3525);
WIRE 17 -1 (-5875 3425)(-5875 3475);
WIRE 17 -1 (-5875 3375)(-5875 3425);
WIRE 17 -1 (-5875 3025)(-5875 3375);
WIRE 17 -1 (-5875 2975)(-5875 3025);
WIRE 17 -1 (-5875 2925)(-5875 2975);
WIRE 17 -1 (-5875 2925)(-5875 2875);
WIRE 17 -1 (-2125 3575)(-1200 3575);
FORCEPROP 2 LAST SIG_NAME P3E_CPU0_PE1_PCH_TXP<15:8>
J 0
(-1935 3585);
DISPLAY 0.617021 (-1935 3585);
PAINT ORANGE (-1935 3585);
WIRE 17 -1 (-2125 3525)(-2125 3575);
WIRE 17 -1 (-2125 3475)(-2125 3525);
WIRE 17 -1 (-2125 3425)(-2125 3475);
WIRE 17 -1 (-2125 3375)(-2125 3425);
WIRE 17 -1 (-2125 3025)(-2125 3375);
WIRE 17 -1 (-2125 2975)(-2125 3025);
WIRE 17 -1 (-2125 2925)(-2125 2975);
WIRE 17 -1 (-2125 2875)(-2125 2925);
WIRE 17 -1 (-2575 2675)(-2575 2625);
WIRE 17 -1 (-2575 3725)(-1200 3725);
FORCEPROP 2 LAST SIG_NAME P3E_CPU0_PE1_PCH_TXN<15:8>
J 0
(-1935 3735);
DISPLAY 0.617021 (-1935 3735);
PAINT ORANGE (-1935 3735);
WIRE 17 -1 (-2575 3725)(-2575 3275);
WIRE 17 -1 (-2575 2675)(-2575 2725);
WIRE 17 -1 (-2575 2775)(-2575 2725);
WIRE 17 -1 (-2575 3225)(-2575 3275);
WIRE 17 -1 (-2575 3175)(-2575 3225);
WIRE 17 -1 (-2575 3125)(-2575 2775);
WIRE 17 -1 (-2575 3125)(-2575 3175);
WIRE 16 -1 (-3350 3250)(-2675 3250);
WIRE 16 -1 (-5775 3500)(-4850 3500);
WIRE 16 -1 (-2225 3350)(-3350 3350);
WIRE 16 -1 (-5775 2900)(-4850 2900);
WIRE 16 -1 (-5775 3000)(-4850 3000);
WIRE 16 -1 (-2225 1900)(-3350 1900);
WIRE 16 -1 (-2225 1950)(-3350 1950);
WIRE 16 -1 (-2225 2000)(-3350 2000);
WIRE 16 -1 (-3350 2350)(-2225 2350);
WIRE 16 -1 (-3350 2400)(-2225 2400);
WIRE 16 -1 (-3350 2450)(-2225 2450);
WIRE 16 -1 (-3350 2500)(-2225 2500);
WIRE 16 -1 (-2675 2650)(-3350 2650);
WIRE 16 -1 (-2675 2700)(-3350 2700);
WIRE 16 -1 (-5500 2600)(-4850 2600);
WIRE 16 -1 (-5500 2200)(-4850 2200);
WIRE 16 -1 (-4850 2250)(-5500 2250);
WIRE 16 -1 (-3350 3200)(-2675 3200);
WIRE 16 -1 (-2675 3150)(-3350 3150);
WIRE 16 -1 (-2675 2750)(-3350 2750);
WIRE 16 -1 (-2675 2600)(-3350 2600);
WIRE 16 -1 (-2675 2250)(-3350 2250);
WIRE 16 -1 (-2225 3500)(-3350 3500);
WIRE 16 -1 (-2225 3450)(-3350 3450);
WIRE 16 -1 (-2225 3400)(-3350 3400);
WIRE 16 -1 (-5500 2750)(-4850 2750);
WIRE 16 -1 (-4850 2700)(-5500 2700);
WIRE 16 -1 (-5500 2650)(-4850 2650);
WIRE 16 -1 (-5500 2150)(-4850 2150);
WIRE 16 -1 (-5500 2100)(-4850 2100);
WIRE 16 -1 (-5775 3450)(-4850 3450);
WIRE 16 -1 (-4850 2500)(-5775 2500);
WIRE 16 -1 (-5775 2450)(-4850 2450);
WIRE 16 -1 (-5775 2400)(-4850 2400);
WIRE 16 -1 (-5775 2350)(-4850 2350);
WIRE 16 -1 (-5500 1650)(-4850 1650);
WIRE 16 -1 (-4850 1600)(-5500 1600);
WIRE 16 -1 (-5775 2000)(-4850 2000);
WIRE 16 -1 (-2675 3100)(-3350 3100);
WIRE 16 -1 (-5775 2950)(-4850 2950);
WIRE 16 -1 (-2225 2900)(-3350 2900);
WIRE 16 -1 (-3350 3000)(-2225 3000);
WIRE 16 -1 (-3350 2950)(-2225 2950);
WIRE 16 -1 (-3350 2850)(-2225 2850);
WIRE 16 -1 (-5775 3350)(-4850 3350);
WIRE 16 -1 (-5500 3100)(-4850 3100);
WIRE 16 -1 (-5775 3400)(-4850 3400);
WIRE 16 -1 (-3350 2200)(-2675 2200);
WIRE 16 -1 (-5775 2850)(-4850 2850);
WIRE 16 -1 (-5500 3250)(-4850 3250);
WIRE 16 -1 (-4850 3200)(-5500 3200);
WIRE 16 -1 (-5500 3150)(-4850 3150);
WIRE 16 -1 (-2675 1750)(-3350 1750);
WIRE 16 -1 (-2675 1700)(-3350 1700);
WIRE 16 -1 (-3350 1650)(-2675 1650);
WIRE 16 -1 (-2675 1600)(-3350 1600);
WIRE 16 -1 (-2225 1850)(-3350 1850);
WIRE 16 -1 (-3350 2150)(-2675 2150);
WIRE 16 -1 (-3350 2100)(-2675 2100);
WIRE 16 -1 (-5775 1950)(-4850 1950);
WIRE 16 -1 (-5775 1900)(-4850 1900);
WIRE 16 -1 (-4850 1850)(-5775 1850);
WIRE 16 -1 (-5500 1750)(-4850 1750);
WIRE 16 -1 (-5500 1700)(-4850 1700);
FORCENOTE
PCH PCIEUP/SS STEERING OPTION
(-1950 3400) 0;
DISPLAY LEFT (-1950 3400);
DISPLAY 1.021277 (-1950 3400);
PAINT PURPLE (-1950 3400);
FORCENOTE
TO: 
(-1950 1450) 0;
DISPLAY LEFT (-1950 1450);
DISPLAY 1.021277 (-1950 1450);
PAINT PURPLE (-1950 1450);
FORCENOTE
PCH PCIEUP/SS STEERING OPTION
(-1950 1350) 0;
DISPLAY LEFT (-1950 1350);
DISPLAY 1.021277 (-1950 1350);
PAINT PURPLE (-1950 1350);
FORCENOTE
TO: 
(-7050 1400) 0;
DISPLAY LEFT (-7050 1400);
DISPLAY 1.021277 (-7050 1400);
PAINT PURPLE (-7050 1400);
FORCENOTE
PCH PCIEUP/SS STEERING OPTION
(-7050 1300) 0;
DISPLAY LEFT (-7050 1300);
DISPLAY 1.021277 (-7050 1300);
PAINT PURPLE (-7050 1300);
FORCENOTE
PCH PCIEUP/SS STEERING OPTION
(-7050 3300) 0;
DISPLAY LEFT (-7050 3300);
DISPLAY 1.021277 (-7050 3300);
PAINT PURPLE (-7050 3300);
FORCENOTE
TO:
(-7050 3400) 0;
DISPLAY LEFT (-7050 3400);
DISPLAY 1.021277 (-7050 3400);
PAINT PURPLE (-7050 3400);
FORCENOTE
TO:
(-1950 3500) 0;
DISPLAY LEFT (-1950 3500);
DISPLAY 1.021277 (-1950 3500);
PAINT PURPLE (-1950 3500);
FORCENOTE
SKYLAKE - SKT0 - 10 OF 21
(-1650 150) 0;
DISPLAY LEFT (-1650 150);
DISPLAY 1.021277 (-1650 150);
PAINT RED (-1650 150);
FORCENOTE
ROOM=CPU0
(-7925 375) 0;
DISPLAY LEFT (-7925 375);
DISPLAY 1.723404 (-7925 375);
PAINT PURPLE (-7925 375);
FORCENOTE
BOM_COST=PROC_SOCKET
(-7925 250) 0;
DISPLAY LEFT (-7925 250);
DISPLAY 1.723404 (-7925 250);
PAINT PURPLE (-7925 250);
QUIT
